# GTI_MB_BOM.xlsx — VR_RTT (bom)
| Part Number | Item Description | Mfr. Name | Mfr. PN | Qty | Location |
| AJ033040001 | IC CTRL(68P)CYUSB3304-68LTXI(QFN) | CYPRESS SEMICONDUCTOR (AgigA Tech) | CYUSB3304-68LTXI | 1 | U6001 |
| AJ051610U03 | IC(354P)PT5161LRS(FC-CSP) | Astera Labs, Inc. | PT5161LRS | 8 | U6010,U6011,U6012,U6013,U6014,U6015,U6016,U6017 |
| AKE30Z00613 | IC(8P) EEPROM M24128-BWMN6TP(SO8) | SGS-THOMSON(STMicroelectronics) | M24128-BWMN6TP | 3 | U1,U6003,U64 |
| AKE33Z00600 | IC EEPROM(8P)M24M02-DRMN6TP(SO) | SGS-THOMSON(STMicroelectronics) | M24M02-DRMN6TP | 8 | U11,U12,U15,U16,U17,U19,U20,U21 |
| AL000128K00 | IC OTHER(16P)ADC128D818CIMTX/NOPB(TSSOP) | TEXAS INSTRUMENTS SUPPLY CO., | ADC128D818CIMTX/NOPB | 2 | U269,U51 |
| AL000230001 | IC OTHER (16P) INA230AIRGTR (QFN 3X3) | TEXAS INSTRUMENTS SUPPLY CO., | INA230AIRGTR | 9 | U263,U264,U265,U266,U276,U52,U55,U56,U6005 |
| AL000304005 | IC(12P)PI4ULS3V304AZMAEX(UQFN) | DIODES TAIWAN CO.,LTD. | PI4ULS3V304AZMAEX | 1 | U54 |
| AL000304K01 | IC OTHER(8P) PI6CV304LEX(TSSOP) | PERICOM SEMICONDUCTOR CORPORATION | PI6CV304LEX | 1 | U90 |
| AL000331011 | IC OTHER(5P) AP331AWG-7 (SOT25) | DIODES TAIWAN CO.,LTD. | AP331AWG-7 | 2 | U8008,U8010 |
| AL000451003 | IC OTHER(33P) 9ZXL0451EKILFT(VFQFPN) | INTEGRATED DEVICE TECHNOLOGY,INC. | 9ZXL0451EKILFT | 2 | U10,U314 |
| AL000852001 | IC (29P) GL852G-OHY60(QFN) | Genesys Logic, Inc. (Genesys Logic America, Inc.) | GL852G-OHY60 | 1 | U268 |
| AL001G66000 | IC(5P) 74LVC1G66GV(SOT753) | PHILIPS  LTD,. | 74LVC1G66GV | 2 | U320,U321 |
| AL002G07003 | IC OTHER(6P)74LVC2G07DW-7(SOT-363) | DIODES TAIWAN CO.,LTD. | 74LVC2G07DW-7 | 8 | U134,U211,U255,U257,U308,U58,U59,U8 |
| AL002G07006 | IC OTHER(6P) SN74LVC2G07DCKR(SC70-6) | TEXAS INSTRUMENTS SUPPLY CO., | SN74LVC2G07DCKR | 3 | U259,U29,U40 |
| AL003126K08 | IC OTHER(14P) 74CBTLV3126PW(TSSOP) | NXP semiconductors | 74CBTLV3126PW | 4 | U222,U223,U67,U7 |
| AL003284002 | IC (37P)NCP3284AMNTXG(PQFN) | ON SEMICONDUCTOR | NCP3284AMNTXG | 1 | PU9 |
| AL004307000 | IC OTHER(8P) LTC4307CMS8#TRPBF(MSOP) | LINEAR TECHNOLOGY CORPORATION | LTC4307CMS8#TRPBF | 4 | U175,U192,U194,U200 |
| AL005990A03 | IC(45P)MP5990GMA-1111-Z(LGA) | Monolithic Power Systems, Inc (MPS International Ltd.) | MP5990GMA-1111-Z | 1 | PU289 |
| AL005991A00 | IC(32P)MP5991GLU-Z(LGA) | Monolithic Power Systems, Inc (MPS International Ltd.) | MP5991GLU-Z | 4 | PU287,PU288,PU296,PU297 |
| AL0075BD000 | IC OTHER (8P) LM75BD(SO8) | NXP semiconductors | LM75BD | 4 | U270,U271,U272,U273 |
| AL008626000 | IC CTRL(14P)MPQ8626GD-Z(QFN) | Monolithic Power Systems, Inc (MPS International Ltd.) | MPQ8626GD-Z | 2 | PU6000,PU6001 |
| AL008633005 | IC(21P)MPQ8633BGLE-C838-Z(QFN) | Monolithic Power Systems, Inc (MPS International Ltd.) | MPQ8633BGLE-C838-Z | 4 | PU3,PU57,PU6500,PU6501 |
| AL008633007 | IC(21P)MPQ8633AGLE-C807-Z(QFN) | Monolithic Power Systems, Inc (MPS International Ltd.) | MPQ8633AGLE-C807-Z | 2 | PU55,U326 |
| AL009306K04 | IC OTHER(8P)PCA9306DP1(TSSOP) | NXP semiconductors | PCA9306DP1 | 1 | U98 |
| AL009539K07 | IC OTHER(24P)PCA9539RPW(TSSOP) | NXP semiconductors | PCA9539RPW | 1 | U181 |
| AL009548K02 | IC OTHER(24P) TCA9548APWR(TSSOP) | TEXAS INSTRUMENTS SUPPLY CO., | TCA9548APWR | 4 | U22,U36,U39,U6020 |
| AL009617K02 | IC OTHER(8P) PCA9617ADP(TSSOP) | NXP semiconductors | PCA9617ADP | 6 | U2,U235,U236,U27,U279,U96 |
| AL009818001 | IC OTHER(3P)RT9818C-44GV(SOT23-3) | RICHTEK TECHNOLOGY CORPORATION | RT9818C-44GV | 1 | U100 |
| AL012902001 | IC OTHER(30P)PI3EQX12902AZLEX(TQFN) | PERICOM SEMICONDUCTOR CORPORATION | PI3EQX12902AZLEX | 1 | U237 |
| AL015080B00 | IC(28P)MAX15090BEWI+T(WLP) | MAXIM JAPAN CO.,LTD(DALLAS SEMICONDUCTOR CORP.) | MAX15090BEWI+T | 7 | PU200,PU201,PU202,PU203,PU294,PU295,PU300 |
| AL02T245000 | IC OTHER (10P) SN74AVC2T245RSWR(UQFN) | TEXAS INSTRUMENTS SUPPLY CO., | SN74AVC2T245RSWR | 3 | U146,U147,U152 |
| AL033202001 | IC OTHER(24P)PI6CG33202CZDIEX-13R(TQFN) | DIODES TAIWAN CO.,LTD. | PI6CG33202CZDIEX-13R | 1 | U247 |
| AL04T774K00 | IC OTHER(16P) SN74AVC4T774PWR(TSSOP) | TEXAS INSTRUMENTS SUPPLY CO., | SN74AVC4T774PWR | 6 | U116,U148,U149,U150,U151,U53 |
| AL080929000 | IC(3P) APX809-29SAG-7(SOT23) | DIODES TAIWAN CO.,LTD. | APX809-29SAG-7 | 3 | U6006,U8001,U8002 |
| AL099390004 | IC CTRL(41P) ISL99390FRZ-TR5935(QFN) | Renesas Technology Taiwan Co., Ltd. | ISL99390FRZ-TR5935 | 46 | PU10,PU11,PU13,PU14,PU15,PU16,PU17,PU18,PU19,PU2,PU20,PU22,PU23,PU24,PU26,PU27,PU28,PU29,PU30,PU31,PU32,PU33,PU35,PU36,PU37,PU38,PU39,PU4,PU40,PU43,PU44,PU45,PU46,PU47,PU48,PU49,PU5,PU50,PU51,PU52,PU53,PU6,PU6503,PU6504,PU6511,PU6512 |
| AL1G0007001 | IC OTHER(5P) 74LVC1G07GV(SOT753) | NXP semiconductors | 74LVC1G07GV | 4 | U104,U157,U218,U219 |
| AL1G0007024 | IC OTHER(5P) SN74LVC1G07DBVR(SOT23) | TEXAS INSTRUMENTS SUPPLY CO., | SN74LVC1G07DBVR | 10 | U101,U124,U28,U3,U30,U33,U34,U82,U86,U92 |
| AL1G0008020 | IC OTHER(5P) 74LVC1G08W5-7(SOT25) | DIODES TAIWAN CO.,LTD. | 74LVC1G08W5-7 | 7 | U23,U278,U31,U35,U9001,U9050,U9051 |
| AL1G0017K01 | IC OTHER(5P) 74LVC1G17GW(TSSOP) | NXP semiconductors | 74LVC1G17GW | 3 | U207,U44,U75 |
| AL1G0126009 | IC OTHER(5P) 74LVC1G126SE-7 (SOT353) | DIODES TAIWAN CO.,LTD. | 74LVC1G126SE-7 | 8 | U204,U217,U224,U225,U239,U286,U66,U8082 |
| AL2G0017005 | IC(6P) 74LVC2G17GW (SC-88) | PHILIPS  LTD,. | 74LVC2G17GW | 6 | U195,U196,U252,U253,U256,U316 |
| AL2G0066C00 | IC OTHER(8P) SN74AUC2G66DCTR (SSOP) | TEXAS INSTRUMENTS SUPPLY CO., | SN74AUC2G66DCTR | 4 | U13,U14,U153,U154 |
| AL3CSW12000 | IC(10P)PI3CSW12ZUAEX(UQFN) | DIODES TAIWAN CO.,LTD. | PI3CSW12ZUAEX | 14 | U105,U106,U107,U108,U4,U41,U42,U43,U45,U46,U47,U48,U49,U6 |
| AL404025013 | IC OTHER(3P)LM4040AIM3X-2.5/NOPB(SOT23) | TEXAS INSTRUMENTS SUPPLY CO., | LM4040AIM3X-2.5/NOPB | 2 | U8007,U8009 |
| ALLV4052K19 | IC OTHERS(16P)74LV4052PW(TSSOP) | PHILIPS  LTD,. | 74LV4052PW | 2 | U160,U212 |
| ALLVC1G1000 | IC OTHER(6P)SN74LVC1G11DCKR(SC70) | TEXAS INSTRUMENTS SUPPLY CO., | SN74LVC1G11DCKR | 1 | U38 |
| ALSB3157000 | IC OTHER(6P)NC7SB3157P6X(SC70-6) | FAIRCHILD SEMICONDUCTOR | NC7SB3157P6X | 1 | U8000 |
| ALVC1G32007 | IC OTHER(5P) 74LVC1G32GW (SC70-5) | PHILIPS  LTD,. | 74LVC1G32GW | 3 | U248,U37,U9002 |
| ARF0TGP4003 | PROG IC(41P)RAA229621GNP#HA0(QFN) | Renesas Technology Taiwan Co., Ltd. | RAA229621GNP#HA0 | 2 | PU21,PU54 |
| ARF0TGP4021 | PROG IC(484P)LCMXO3LF-9400C-5BG48(CABGA) | LATTICE SEMICONDUCTOR CORP., | LCMXO3LF-9400C-5BG484C | 1 | U18 |
| ARF0TGP4015 | PROG IC (49P) RAA229620GNP#HA0 (QFN) | Renesas Technology Taiwan Co., Ltd. | RAA229620GNP#HA0 | 4 | PU12,PU25,PU34,PU42 |
| ARF0TGP4016 | PROG IC (41P) ISL69260IRAZ-T (8A9E3594) | Renesas Technology Taiwan Co., Ltd. | ISL69260IRAZ-T | 2 | PU6502,PU6510 |
| BAM01380023 | TRANS MOS NX138BK(60V,265MA,310MW) | NXP semiconductors | NX138BK | 4 | Q12,Q29,Q30,Q61 |
| BAM01380032 | TRANS MOSFET BSS138DW-7-F(50V,200MA) | DIODES TAIWAN CO.,LTD. | BSS138DW-7-F | 3 | Q18,Q19,Q27 |
| BAM138K0000 | TRANS MOSFET BSS138K(50V,0.22A,0.35W) | FAIRCHILD SEMICONDUCTOR | BSS138K | 9 | PQ14,PQ15,PQ16,PQ17,Q62,Q63,Q64,U24,U32 |
| BAM138K0003 | TRANS MOSFET PJT138K(50V,0.36A,0.236W) | PAN JIT INTERNATIONAL INC. | PJT138K | 57 | Q1,Q101,Q102,Q103,Q104,Q106,Q107,Q108,Q118,Q119,Q123,Q124,Q125,Q126,Q127,Q128,Q129,Q130,Q131,Q132,Q133,Q134,Q135,Q136,Q137,Q144,Q145,Q146,Q148,Q3,Q37,Q50,Q6000,Q67,Q69,Q70,Q71,Q72,Q74,Q75,Q78,Q79,Q80,Q8000,Q8001,Q81,Q83,Q84,Q85,Q86,Q87,Q9000,Q9001,Q9002,Q9003,Q95,Q96 |
| BAM34150008 | TRANS MOS PJA3415AE(-20V,-4.3A,1.25W) | PAN JIT INTERNATIONAL INC. | PJA3415AE | 4 | PQ10,PQ11,PQ12,PQ13 |
| BAM70020002 | TR MOSFET 2N7002K(60V,300MA,0.35W)SOT-23 | PAN JIT INTERNATIONAL INC. | 2N7002K | 6 | Q39,Q54,U158,U190,U290,U324 |
| BAM70020047 | TRANS MOS 2N7002KDW(60V115MA,0.2W)SOT363 | PAN JIT INTERNATIONAL INC. | 2N7002KDW | 5 | Q11,Q2,Q28,Q4,Q8 |
| BAMNR580000 | TRANS MOS PSMNR58-30YLH(30V,380A,333W) | Nexperia B.V. | PSMNR58-30YLH | 2 | Q56,Q57 |
| BC000340Z30 | DIODE SMD B340A-13-F(40V,3A)SCHOTTKY | DIODES TAIWAN CO.,LTD. | B340A-13-F | 7 | PD102,PD103,PD108,PD109,PD112,PD113,PD116 |
| BC015P3SZ00 | DIODE SMD SS15P3S-M3/86A(30V,15A) | SILICONIX TAIWAN LTD.(VISHAY SILICONIX ; VISHAY TEMIC ; VISHAY TELFUNKEN)Vishay Intertechnology Corporation Taiwan | SS15P3S-M3/86A | 1 | PD111 |
| BC0BAT54Z53 | DIODE BAT54-7-F(30V,200MA SCHOTTKY) | DIODES TAIWAN CO.,LTD. | BAT54-7-F | 1 | D1 |
| BC0MDJ14000 | DIODE SMD 5.0SMDJ14A(14V,216A,5000W) | LITTELFUSE INC. | 5.0SMDJ14A | 2 | PD13,PD15 |
| BCBAT54CZ13 | DIODE SMD BAT54CW(30V,0.2A,SOT323) | PAN JIT INTERNATIONAL INC. | BAT54CW | 1 | U166 |
| BCSMF14AZ01 | DIODE SMF14A(14V,8.6A)SOD-123FL | LITTELFUSE INC. | SMF14A | 4 | PD101,PD107,PD114,PD115 |
| BEBL0172Z00 | LED SMD(2P) BLUE(LTST-C281TBKT-5A) | LITEON ELECTRONIC CO., LTD. | LTST-C281TBKT-5A | 26 | D46,D49,D5,D6000,D73,D74,D75,D76,D77,D78,D79,D80,D8000,D8001,D81,D82,D83,D84,D85,D88,D9,D91,D93,D96,D98,D99 |
| BEYL0159Z00 | LED SMD(2P)YELLOW(LTST-C190KSKT-P) | LITE-ON  CORP.(LITE-ON IT CORPORATION)Lite-On Semiconductor Corp. | LTST-C190KSKT-P | 4 | D6,D7,D8,D8002 |
| BF650000032 | OSC SMD 50MHZ(25PPM,15PF,3.3V)FK5000023 | ECERA COMTEK CORPORATION (Pericom SaRonix Ecera Technology Corporation) P.S.E | FK5000023 | 1 | OSC1 |
| BG6120000B0 | XTAL 12MHZ(+-20PPM,10PF)8Z12000006 | TAIWAN X'TAL CORPATION (TXC Corporation) | 8Z12000006 | 1 | Y8004 |
| BG6250000L4 | XTAL SMD 25MHZ(+-10PPM,8PF)E3SB25E000004 | HANGZHOU HOSONIC ELECTRONIC CO.,LTD (Hosonic Electronic Co., Ltd.) | E3SB25E000004E | 1 | Y8003 |
| BG626000049 | XTAL 26MHZ(10PPM,11PF)8Z26000054 | TAIWAN X'TAL CORPATION (TXC Corporation) | 8Z26000054 | 1 | Y9 |
| BG632768012 | CRYSTAL SMD 32.768KHZ(+-20PPM,12.5PF) | TAIWAN X'TAL CORPATION (TXC Corporation) | 9H03220009 | 1 | Y3 |
| BG648000076 | XTAL SMD 48MHZ(10PPM, 12PF)FL4800106 | DIODES TAIWAN CO.,LTD. | FL4800106 | 2 | Y2,Y4 |
| CC71003MZ30 | CAP OS SMD 100U 16V(20%,ESR27,5*5.8)NPN | NIPPON CHEMI-CON | APXG160ARA101ME61G | 4 | PC473,PC6561,PC6619,PC6810 |
| CC72201MZ28 | CAP OS SMD 220U 6.3V(20%,ESR12,5*5.8)NPN | NIPPON CHEMI-CON | APXF6R3ARA221ME611 | 1 | PC1845 |
| CC72703MZ11 | CAPOS SMD 270U 16V(20%,ESR10,6.3*7.7)NPN | NIPPON CHEMI-CON | APXJ160ARA271MF80J | 5 | PC390,PC393,PC454,PC6800,PC6801 |
| CC7390JMZ13 | CAP OS SMD 390U 2.5V(20%,ESR10,5*5.8)NPN | NIPPON CHEMI-CON | APXF2R5ARA391ME611 | 22 | PC115,PC228,PC229,PC230,PC530,PC531,PC532,PC6513,PC6532,PC6571,PC6572,PC6573,PC6574,PC6629,PC6630,PC6631,PC6632,PC6804,PC6805,PC801,PC803,PC89 |
| CH0106F0B00 | CAP CHIP 10PF 50V(+-1%,NPO,0402) | JOHANSON DIELETRICS,INC. | 500R07S100FV4T | 3 | C238,C239,PC569 |
| CH01206JB05 | CAP CHIP 12P 50V(+-5%,C0G,0402) | ACER PERIPHERALS INC.(Darfon Electronics Corp.) Darfon Precisions(Suzhou)Co.,LTD | C1005NP0120JGT | 1 | C91 |
| CH01506JB06 | CAP CHIP 15P 50V(+-5% C0G 0402) | ACER PERIPHERALS INC.(Darfon Electronics Corp.) Darfon Precisions(Suzhou)Co.,LTD | C1005NP0150JGT | 3 | C2029,C2030,C93 |
| CH03306JB04 | CAP CHIP 33P 50V(+-5%,NPO,0402) | ACER PERIPHERALS INC.(Darfon Electronics Corp.) Darfon Precisions(Suzhou)Co.,LTD | C1005NP0330JGT | 3 | C1510,C1511,C1512 |
| CH04706JB01 | CAP CHIP 47P 50V(+-5%,NPO,0402) | ACER PERIPHERALS INC.(Darfon Electronics Corp.) Darfon Precisions(Suzhou)Co.,LTD | C1005NP0470JGT | 1 | PC1877 |
| CH-10KMEE00 | CAP CHIP 1U 4V(+-20%,X6S,0201) | MURATA ERIE N.A. INC TAIWAN BRANCH Okayama Murata Mfg.Co.,Ltd.Wakura Murata Mfg. Co., Ltd. (Peregrine Semiconductor Corp) | GRM033C80G105M | 136 | C1000,C1006,C1013,C1015,C1016,C1017,C1018,C1019,C1020,C1024,C1027,C1031,C1039,C1046,C1050,C123,C125,C126,C135,C138,C185,C186,C187,C188,C190,C201,C202,C203,C204,C222,C243,C257,C265,C280,C285,C289,C293,C294,C301,C306,C307,C314,C315,C326,C330,C337,C342,C346,C353,C374,C375,C376,C382,C384,C386,C387,C389,C390,C391,C394,C407,C415,C418,C422,C423,C425,C440,C441,C442,C448,C452,C453,C454,C455,C456,C459,C460,C470,C485,C488,C491,C492,C497,C512,C513,C514,C521,C525,C526,C528,C529,C539,C542,C545,C555,C562,C570,C573,C577,C581,C597,C598,C599,C607,C609,C613,C618,C620,C621,C622,C624,C643,C647,C653,C654,C655,C660,C673,C676,C677,C779,C781,C783,C786,C787,C788,C792,C793,C797,C975,C978,C979,C980,C983,C998,C999 |
| CH11006JB00 | CAP CHIP 100P 50V(+-5%,NPO,0402) | ACER PERIPHERALS INC.(Darfon Electronics Corp.) Darfon Precisions(Suzhou)Co.,LTD | C1005NP0101JGT | 2 | C1209,PC132 |
| CH11506JB08 | CAP CHIP 150P 50V(+-5%,NPO,0402) | ACER PERIPHERALS INC.(Darfon Electronics Corp.) Darfon Precisions(Suzhou)Co.,LTD | C1005NP0151JGT | 2 | PC6515,PC6534 |
| CH12206JB00 | CAP CHIP 220P 50V(+-5%,COG,0402) | AVX CORPARATION CO., LTD. | 04025A221JAT2A | 4 | C363,C364,C62,C63 |
| CH12206KB14 | CAP CHIP 220P 50V(+-10%,X7R,0402) | ACER PERIPHERALS INC.(Darfon Electronics Corp.) Darfon Precisions(Suzhou)Co.,LTD | C1005X7R221KGT | 3 | PC2182,PC259,PC64 |
| CH122KM8801 | CAP CHIP 220U 4V(20%,7343,SPCAP)MAT | MATSUSHITA ELECTRONICS CORPORATION (PANASONIC)Wuxi Matsushita Battery Co., Ltd (Panasonic Communication Corp. of the Phils) Panasonic Precision Devices Co.,Ltd. | EEFSX0G221ER | 20 | PC100,PC102,PC103,PC105,PC106,PC108,PC275,PC276,PC277,PC279,PC387,PC388,PC389,PC391,PC494,PC495,PC496,PC498,PC97,PC98 |
| CH1336K1B02 | CAP CHIP 330P 50V(+-10%,X7R,0402) | ACER PERIPHERALS INC.(Darfon Electronics Corp.) Darfon Precisions(Suzhou)Co.,LTD | C1005X7R331KGT | 2 | PC6019,PC852 |
| CH14706KB18 | CAP CHIP 470P 50V(+-10%,X7R,0402) | ACER PERIPHERALS INC.(Darfon Electronics Corp.) Darfon Precisions(Suzhou)Co.,LTD | C1005X7R471KGT | 13 | C6028,PC198,PC250,PC253,PC367,PC368,PC469,PC472,PC523,PC643,PC6607,PC77,PC78 |
| CH21006JB10 | CAP CHIP 1000P 50V(+-5%,X7R,0402) | ACER PERIPHERALS INC.(Darfon Electronics Corp.) Darfon Precisions(Suzhou)Co.,LTD | C1005X7R102JGT | 33 | C109,C197,C242,C249,C461,C468,C5000,C5001,C5002,C5003,C5004,C5005,C5006,C5009,C5010,C5011,C5012,C5013,C5014,C5016,C5017,C5018,C5019,C5020,C5022,C5023,C5024,C642,C6758,C8066,C8069,C8356,C8359 |
| CH2336K1B12 | CAP CHIP 3300P 50V(+-10%,X7R,0402) | ACER PERIPHERALS INC.(Darfon Electronics Corp.) Darfon Precisions(Suzhou)Co.,LTD | C1005X7R332KGT | 18 | PC194,PC244,PC245,PC358,PC361,PC384,PC463,PC464,PC6016,PC639,PC6540,PC6555_1,PC6578_2,PC6600,PC6613_1,PC6634_2,PC68,PC71 |
| CH23906KB14 | CAP CHIP 3900P 50V(+-10%,X7R,0402) | ACER PERIPHERALS INC.(Darfon Electronics Corp.) Darfon Precisions(Suzhou)Co.,LTD | C1005X7R392KGT | 4 | PC2150,PC2215,PC2237,PC4056 |
| CH2686K1B01 | CAP CHIP 6800P 50V(+-10%,X7R,0402) | ACER PERIPHERALS INC.(Darfon Electronics Corp.) Darfon Precisions(Suzhou)Co.,LTD | C1005X7R682KGT | 3 | PC2089,PC2151,PC2216 |
| CH-276B0B00 | CAP CHIP 2.7P 50V(+-0.1P,NPO,0402) | ACER PERIPHERALS INC.(Darfon Electronics Corp.) Darfon Precisions(Suzhou)Co.,LTD | C1005NP0279BGTS | 2 | C236,C237 |
| CH30106KB19 | CAP CHIP 0.001U 50V(10%,X7R,0402) | AVX CORPARATION CO., LTD. | 04025C102KAT2A | 15 | C604,C605,C6054,C6056,C6058,C6060,C6062,C6067,C6069,C6071,C6073,C6075,C85,C87,PC2192 |
| CH31006KB18 | CAP CHIP 0.01U 50V(+-10%,X7R,0402) | ACER PERIPHERALS INC.(Darfon Electronics Corp.) Darfon Precisions(Suzhou)Co.,LTD | C1005X7R103KGT | 23 | C551,C6033,C6035,C6037,C6039,C6040,C6045,C6049,C6051,C6053,C6055,C6057,C6059,C6061,C6063,C6068,C6070,C6072,C6074,C6076,C6080,PC2189,PC2190 |
| CH3224K1B01 | CAP CHIP 0.022U 25V(+-10%,X7R,0402) | ACER PERIPHERALS INC.(Darfon Electronics Corp.) Darfon Precisions(Suzhou)Co.,LTD | C1005X7R223KFT | 2 | PC153,PC258 |
| CH3474K1B04 | CAP CHIP 0.047U 25V(+-10% X7R 0402) | ACER PERIPHERALS INC.(Darfon Electronics Corp.) Darfon Precisions(Suzhou)Co.,LTD | C1005X7R473KFT | 1 | PC2193 |
| CH3683K1B09 | CAP CHIP 0.068UF 16V(+-10%,X7R 0402) | ACER PERIPHERALS INC.(Darfon Electronics Corp.) Darfon Precisions(Suzhou)Co.,LTD | C1005X7R683KET | 5 | PC2184,PC2185,PC2191,PC2226,PC2227 |
| CH-3916TB01 | CAP CHIP 3.9P 50V(+-0.1P,NPO,0402) | ACER PERIPHERALS INC.(Darfon Electronics Corp.) Darfon Precisions(Suzhou)Co.,LTD | C1005NP0399BGT | 2 | C213,C214 |
| CH4102K6E00 | CAP CHIP 0.1U 10V(+-10%,X7S,0201) | ACER PERIPHERALS INC.(Darfon Electronics Corp.) Darfon Precisions(Suzhou)Co.,LTD | C0603X7S104KDT | 186 | C1001,C1002,C1003,C1004,C1005,C1007,C1008,C1009,C1010,C1011,C1012,C1014,C1021,C1035,C1043,C1047,C1048,C1051,C1052,C1053,C1055,C1057,C1066,C1067,C1068,C1069,C1070,C1071,C1072,C1073,C129,C130,C131,C133,C134,C137,C139,C141,C184,C189,C191,C192,C198,C205,C206,C217,C228,C253,C260,C264,C266,C281,C282,C283,C287,C288,C290,C291,C292,C300,C311,C312,C313,C316,C319,C322,C334,C340,C341,C344,C349,C350,C365,C377,C378,C379,C380,C381,C383,C385,C388,C392,C393,C395,C396,C397,C400,C403,C411,C421,C426,C427,C428,C430,C443,C444,C445,C446,C447,C449,C450,C451,C457,C458,C462,C463,C464,C473,C477,C481,C493,C495,C496,C498,C500,C515,C516,C517,C519,C520,C522,C523,C524,C538,C540,C541,C543,C544,C558,C566,C576,C578,C580,C582,C583,C585,C600,C601,C602,C603,C606,C608,C610,C614,C615,C616,C617,C619,C623,C627,C631,C635,C650,C657,C658,C659,C662,C664,C7500,C7501,C7502,C7503,C7504,C7510,C774,C775,C776,C777,C778,C780,C782,C784,C785,C789,C790,C791,C794,C800,C804,C968,C972,C982,C984,C985,C987,C989 |
| CH4103K1B08 | CAP CHIP 0.1U 16V(10%,X7R,0402) | ACER PERIPHERALS INC.(Darfon Electronics Corp.) Darfon Precisions(Suzhou)Co.,LTD | C1005X7R104KET | 44 | C1126,C1127,C1128,C1129,C1131,C1132,C1133,C1134,C1171,C1172,C1173,C1174,C1175,C1176,C1503,C1504,C1505,C1506,C1507,C1508,C1509,C1513,C1514,C1515,C1516,C1517,C1518,C1519,C1521,C1522,C1523,C1554,C1563,C194,C20,C352,C355,C356,C357,C358,C359,C360,C361,C362 |
| CH4104K1B00 | CAP CHIP 0.1U 25V(+-10%,X7R,0402) | EYANG TECHNOLOGY DEVELOPMENT CO., LTD | C0402X7R104K250NTN | 445 | C1,C10,C100,C104,C1058,C1059,C106,C1060,C1061,C1062,C1063,C1064,C1065,C1074,C1075,C108,C1086,C1087,C1088,C1089,C1090,C1091,C1092,C1093,C1094,C1095,C1096,C1097,C11,C1102,C1103,C1104,C1105,C1106,C1107,C1108,C1109,C1110,C1111,C1112,C112,C116,C12,C120,C1235,C1236,C1237,C1238,C1239,C124,C1240,C1274,C1275,C1278,C1279,C128,C1282,C1283,C13,C1305,C132,C1323,C1336,C1337,C1338,C1339,C1347,C1352,C1354,C136,C14,C140,C144,C148,C15,C152,C156,C1592,C16,C160,C164,C1663,C168,C17,C1707,C1708,C1713,C172,C1751,C1754,C1756,C1757,C176,C1766,C1769,C1770,C1772,C1773,C1774,C1775,C1796,C1797,C18,C180,C1802,C1803,C1804,C1809,C1810,C1821,C1822,C1823,C1824,C1825,C1826,C1827,C1831,C1832,C1833,C1834,C1835,C1836,C1837,C1838,C1839,C1840,C1841,C1859,C1860,C1861,C1862,C1863,C1864,C1865,C1866,C1868,C1869,C1870,C1871,C1873,C1874,C1875,C1876,C1877,C1878,C1879,C1880,C1881,C1882,C1886,C1889,C19,C1923,C1924,C1925,C1957,C1958,C1963,C1973,C1974,C1975,C1976,C1977,C1978,C1979,C1988,C1997,C1998,C2,C2010,C2012,C2013,C2014,C2015,C2017,C2018,C2019,C2020,C2021,C2022,C2024,C2027,C2032,C2033,C2034,C2039,C2040,C2046,C2047,C2048,C2049,C2050,C2051,C2052,C2056,C2067,C2069,C2071,C21,C218,C219,C2194,C223,C224,C2257,C226,C23,C2329,C2334,C2339,C2344,C25,C26,C27,C3,C30,C31,C32,C33,C347,C36,C37,C38,C4,C42,C43,C5,C508,C552,C553,C58,C592,C593,C6000,C6003,C6004,C6023,C6024,C6032,C6034,C6036,C6038,C6041,C6044,C6048,C6050,C6052,C6064,C6077,C6081,C6083,C6086,C6087,C611,C612,C629,C639,C640,C641,C6500,C68,C69,C693,C7,C70,C72,C73,C75,C78,C79,C8,C80,C8005,C8006,C8007,C8008,C8009,C81,C84,C88,C90,C9005,C9007,C9008,C9050,C9051,C92,C95,C96,C97,C98,C99,PC10,PC107,PC11,PC111_6,PC113,PC113_4,PC114_3,PC114_6,PC115_4,PC116_3,PC12,PC124_6,PC127,PC127_6,PC128,PC13,PC132_5,PC134_5,PC136,PC136_6,PC14,PC141_6,PC145_7,PC146_8,PC148,PC148_1,PC149_2,PC15,PC150_6,PC153_6,PC175_9,PC176_10,PC177_3,PC178_4,PC1852,PC1853,PC1869,PC193,PC201_1,PC202_2,PC207_1,PC208_2,PC2091,PC2092,PC21,PC2137,PC215,PC2152,PC2217,PC2218,PC222,PC2238,PC243,PC254_1,PC255_2,PC260_1,PC261_2,PC278,PC284_3,PC285_4,PC29,PC290_3,PC293_4,PC306_5,PC309_5,PC317_7,PC318_8,PC325_1,PC326_2,PC338,PC345_9,PC348_3,PC357,PC364,PC373_2,PC374_1,PC375,PC375_1,PC376_2,PC392,PC4,PC403_4,PC404_3,PC405_4,PC408_3,PC422_5,PC425_5,PC435_7,PC436_8,PC438,PC438_1,PC439_2,PC462,PC473_1,PC474_2,PC479,PC479_1,PC482_2,PC497,PC5,PC503_1,PC504_2,PC509_1,PC510_2,PC511,PC544_3,PC545_4,PC551_4,PC552_3,PC566_5,PC570_5,PC577,PC577_7,PC578_8,PC583,PC583_1,PC586_2,PC599,PC6,PC6002,PC6003,PC6004,PC6007,PC605_9,PC609_3,PC62,PC620_9,PC621_10,PC622_3,PC623_4,PC638,PC6514,PC6518,PC6533,PC6537,PC6562,PC6602,PC6620,PC67,PC7,PC74,PC8,PC819,PC83_2,PC84_1,PC85,PC85_1,PC86_2,PC9,PC93,PC95,PC96,PC99 |
| CH4104KEB00 | CAP CHIP 0.1U 25V(+-10%,X6S,0402) | MURATA ERIE N.A. INC TAIWAN BRANCH Okayama Murata Mfg.Co.,Ltd.Wakura Murata Mfg. Co., Ltd. (Peregrine Semiconductor Corp) | GRM155C81E104K | 6 | PC1648,PC1649,PC6000,PC6001,PC6500,PC6519 |
| CH4106K1B01 | CAP CHIP 100NF 50V(+-10%,X7R,0402) | ACER PERIPHERALS INC.(Darfon Electronics Corp.) Darfon Precisions(Suzhou)Co.,LTD | C1005X7R104KGT | 29 | C1042,C1227,C1332,C193,C2179,C61,C6122,C8019,C8022,PC451,PC524,PC6020,PC6021,PC6022,PC6023,PC6543,PC6553_1,PC6563,PC6565,PC6576,PC6584,PC6603,PC6611_1,PC6621,PC6623,PC6640,PC6646,PC6806,PC6807 |
| CH4221MEE01 | CAP CHIP 0.22UF 6.3V(20%,X6S,0201) | MURATA ERIE N.A. INC TAIWAN BRANCH Okayama Murata Mfg.Co.,Ltd.Wakura Murata Mfg. Co., Ltd. (Peregrine Semiconductor Corp) | GRM033C80J224M | 342 | C1098,C1099,C1100,C1101,C1548,C1549,C1550,C1552,C1553,C1555,C1556,C1557,C1558,C1559,C1560,C1565,C1566,C1568,C1569,C1570,C1571,C1572,C1573,C1574,C1575,C1576,C1577,C1578,C1579,C1792,C1793,C1794,C1989,C1990,C1991,C1992,C1993,C1994,C1995,C1996,C2073,C2074,C2075,C2076,C2077,C2078,C41,C44,C46,C47,C56,C6501,C6502,C6503,C6504,C6505,C6506,C6507,C6508,C6509,C6510,C6511,C6512,C6513,C6514,C6515,C6516,C6517,C6518,C6519,C6520,C6521,C6522,C6523,C6524,C6525,C6526,C6527,C6528,C6529,C6530,C6531,C6532,C6533,C6534,C6535,C6536,C6537,C6538,C6539,C6540,C6541,C6542,C6543,C6544,C6545,C6546,C6547,C6548,C6549,C6550,C6551,C6552,C6553,C6554,C6555,C6556,C6557,C6558,C6559,C6560,C6561,C6562,C6563,C6564,C6565,C6566,C6567,C6568,C6569,C6570,C6571,C6572,C6573,C6574,C6575,C6576,C6577,C6578,C6579,C6580,C6581,C6582,C6583,C6584,C6585,C6586,C6587,C6588,C6589,C6590,C6591,C6592,C6593,C6594,C6595,C6596,C6597,C6598,C6599,C6600,C6601,C6602,C6603,C6604,C6605,C6606,C6607,C6608,C6609,C6610,C6611,C6612,C6613,C6614,C6615,C6616,C6617,C6618,C6619,C6620,C6621,C6622,C6623,C6624,C6625,C6626,C6627,C6628,C6629,C6630,C6631,C6632,C6633,C6634,C6635,C6636,C6637,C6638,C6639,C6640,C6641,C6642,C6643,C6644,C6645,C6646,C6647,C6648,C6649,C6650,C6651,C6652,C6653,C6654,C6655,C6656,C6657,C6658,C6659,C6660,C6661,C6662,C6663,C6664,C6665,C6666,C6667,C6668,C6669,C6670,C6671,C6672,C6673,C6674,C6675,C6676,C6677,C6678,C6679,C6680,C6681,C6682,C6683,C6684,C6685,C6686,C6687,C6688,C6689,C6690,C6691,C6692,C6693,C6694,C6695,C6696,C6697,C6698,C6699,C6700,C6701,C6702,C6703,C6704,C6705,C6706,C6707,C6708,C6709,C6710,C6711,C6712,C6713,C6714,C6715,C6716,C6717,C6718,C6719,C6720,C6721,C6722,C6723,C6724,C6725,C6726,C6727,C6728,C6729,C6730,C6731,C6732,C6733,C6734,C6735,C6736,C6737,C6738,C6739,C6740,C6741,C6742,C6743,C6744,C6745,C6746,C6747,C6748,C6749,C6750,C6751,C6752,C6753,C6754,C6755,C6756,C678,C679,C680,C681,C682,C683,C684,C685,C686,C687,C688,C689,C690,C691,C692,C694,C695,C696,C697,C698,C699,C700,C701,C702,C703,C704,C705,C706,C707,C708,C709,C9102,C9103,C9104,C9105 |
| CH4223K1B00 | CAP CHIP 0.22U 16V(10%,X7R,0402) | MURATA ERIE N.A. INC TAIWAN BRANCH Okayama Murata Mfg.Co.,Ltd.Wakura Murata Mfg. Co., Ltd. (Peregrine Semiconductor Corp) | GRM155R71C224K | 46 | PC117,PC121,PC122,PC133,PC137,PC146,PC155,PC156,PC161,PC183,PC186,PC19,PC209,PC217,PC218,PC270,PC271,PC300,PC301,PC314,PC333,PC334,PC353,PC383,PC386,PC413,PC414,PC428,PC445,PC447,PC489,PC490,PC519,PC520,PC560,PC561,PC574,PC593,PC594,PC612,PC630,PC631,PC6507,PC6526,PC92,PC94 |
| CH4224K1B01 | CAP CHIP 0.22U 25V(10%,X7R,0402) | ACER PERIPHERALS INC.(Darfon Electronics Corp.) Darfon Precisions(Suzhou)Co.,LTD | C1005X7R224KFT | 6 | C29,C9226,PC1847,PC568,PC6017,PC641 |
| CH4331KEB01 | CAP CHIP 0.33UF 6.3V(10%,X6S,0402) | ACER PERIPHERALS INC.(Darfon Electronics Corp.) Darfon Precisions(Suzhou)Co.,LTD | C1005X6S334KCT | 4 | C6015,C6016,C6019,C6020 |
| CH-4716TB06 | CAP CHIP 4.7P 50V(+-0.1P,NPO,0402) | ACER PERIPHERALS INC.(Darfon Electronics Corp.) Darfon Precisions(Suzhou)Co.,LTD | C1005NP0479BGT | 2 | C71,C94 |
| CH5101K1B01 | CAP CHIP 1U,6.3V(+-10%,X7R,0402) | ACER PERIPHERALS INC.(Darfon Electronics Corp.) Darfon Precisions(Suzhou)Co.,LTD | C1005X7R105KCT | 4 | PC247,PC363,PC466,PC73 |
| CH5103K1900 | CAP CHIP 1U 16V(+-10%,X7R,0603) | MURATA ERIE N.A. INC TAIWAN BRANCH Okayama Murata Mfg.Co.,Ltd.Wakura Murata Mfg. Co., Ltd. (Peregrine Semiconductor Corp) | GRM188R71C105K | 1 | PC8008 |
| CH5103KEB01 | CAP CHIP 1UF 16V(10%,X6S,0402) | MURATA ERIE N.A. INC TAIWAN BRANCH Okayama Murata Mfg.Co.,Ltd.Wakura Murata Mfg. Co., Ltd. (Peregrine Semiconductor Corp) | GRM155C81C105K | 11 | PC1846,PC200,PC252,PC365,PC471,PC645,PC6544,PC6545,PC6604,PC6605,PC75 |
| CH5104KEB02 | CAP CHIP 1UF 25V(+-10%,X6S,0402) | KYOCERA CORPORATION | CM05X6S105K25AH | 105 | C1564,C1567,C1884,C2007,C2031,C2035,C2041,C2317,C39,C45,C6031,C6043,C6047,C6065,C6078,C6082,PC115_6,PC117_4,PC118,PC118_3,PC126,PC128_6,PC135_5,PC140_6,PC150_1,PC151_2,PC1525,PC154_6,PC179_3,PC180_4,PC1848,PC20,PC2079,PC2085,PC2086,PC2087,PC209_1,PC2093,PC2098,PC210_2,PC2103,PC212,PC2139,PC2140,PC2146,PC2147,PC2181,PC2186,PC2187,PC2188,PC22,PC2207,PC2208,PC2209,PC2210,PC2211,PC2212,PC2223,PC2230,PC2233,PC2234,PC237,PC262_1,PC263_2,PC291_4,PC292_3,PC310_5,PC323_1,PC324_2,PC3272,PC349_3,PC377_1,PC378_2,PC406_3,PC407_4,PC424_5,PC440_1,PC441_2,PC480_2,PC481_1,PC511_1,PC512_2,PC5328,PC550_3,PC553_4,PC569_5,PC584_2,PC585_1,PC6008,PC6009,PC6010,PC6011,PC608_3,PC624_3,PC625_4,PC6505,PC6506,PC6524,PC6525,PC6554_1,PC6577_2,PC6612_1,PC6633_2,PC87_1,PC88_2 |
| CH5222KEB01 | CAP CHIP 2.2UF 10V(+-10%,X6S,0402) | MURATA ERIE N.A. INC TAIWAN BRANCH Okayama Murata Mfg.Co.,Ltd.Wakura Murata Mfg. Co., Ltd. (Peregrine Semiconductor Corp) | GRM155C81A225K | 92 | PC109,PC110,PC111_C1P0_4,PC112,PC112_C1P0_3,PC113_C1P0_6,PC125,PC126_C0P1_6,PC131,PC133_C1P0_5,PC138,PC139_C1P1_6,PC142,PC143,PC144_IOP0_2,PC147_IOP0_1,PC151,PC152_C0P0_6,PC171,PC172,PC173_IOP0_4,PC174_IOP0_3,PC203,PC204,PC205_11P0_1,PC206_11P0_2,PC256,PC257,PC258_C0P1_1,PC259_C0P1_2,PC286,PC287,PC288_C0P1_3,PC289_C0P1_4,PC307,PC308_C0P1_5,PC319,PC320,PC321_SOP1_1,PC322_SOP1_2,PC346,PC347_SOP1_3,PC369,PC370,PC371_C1P1_1,PC372_C1P1_2,PC399,PC400,PC401_C1P1_4,PC402_C1P1_3,PC421,PC423_C1P1_5,PC432,PC433,PC434_IOP1_2,PC437_IOP1_1,PC475,PC476,PC477_C0P0_1,PC478_C0P0_2,PC505,PC506,PC507_11P1_1,PC508_11P1_2,PC546,PC547,PC548_C0P0_3,PC549_C0P0_4,PC567,PC568_C0P0_5,PC579,PC580,PC581_SOP0_1,PC582_SOP0_2,PC606,PC607_SOP0_3,PC616,PC617,PC618_IOP1_4,PC619_IOP1_3,PC6550_09P0_1,PC6551_09P0_2,PC6552,PC6575,PC6609_09P1_1,PC6610,PC6644_09P1_2,PC6645,PC79,PC80,PC81_C1P0_1,PC82_C1P0_2 |
| CH5223KE901 | CAP CHIP 2.2U 16V(+-10%,X6S,0603) | MURATA ERIE N.A. INC TAIWAN BRANCH Okayama Murata Mfg.Co.,Ltd.Wakura Murata Mfg. Co., Ltd. (Peregrine Semiconductor Corp) | GRM188C81C225K | 1 | PC591 |
| CH5471MEB01 | CAP CHIP 4.7UF 6.3V(+-20%,X6S,0402) | MURATA ERIE N.A. INC TAIWAN BRANCH Okayama Murata Mfg.Co.,Ltd.Wakura Murata Mfg. Co., Ltd. (Peregrine Semiconductor Corp) | GRM155C80J475M | 56 | C1034,C1038,C1045,C1054,C1056,C121,C122,C195,C200,C221,C227,C241,C256,C258,C325,C331,C336,C338,C343,C371,C373,C406,C412,C413,C416,C419,C438,C439,C469,C472,C483,C484,C494,C510,C511,C554,C557,C569,C571,C572,C594,C596,C638,C644,C649,C651,C652,C670,C672,C967,C970,C976,C977,C981,C996,C997 |
| CH5473KE902 | CAP CHIP 4.7UF 16V(+-10%,X6S,0603) | MURATA ERIE N.A. INC TAIWAN BRANCH Okayama Murata Mfg.Co.,Ltd.Wakura Murata Mfg. Co., Ltd. (Peregrine Semiconductor Corp) | GRM188C81C475K | 1 | PC581 |
| CH6101MEB01 | CAP CHIP 10UF 6.3V(+-20%,X6S,0402) | KYOCERA CORPORATION | CM05X6S106M06AH | 67 | C1023,C1036,C1037,C1044,C1049,C118,C119,C127,C199,C2038,C2328,C250,C2512,C2515,C254,C261,C2659,C2662,C269,C28,C286,C321,C332,C333,C339,C354,C370,C372,C410,C414,C420,C429,C431,C436,C437,C480,C482,C489,C490,C499,C506,C507,C561,C567,C574,C579,C584,C591,C595,C626,C645,C646,C648,C661,C669,C671,C76,C77,C796,C803,C82,C83,C971,C973,C986,C994,C995 |
| CH6101MEB03 | CAP CHIP 10UF 6.3V(+-20%,X6S,0402)MUR | MURATA ERIE N.A. INC TAIWAN BRANCH Okayama Murata Mfg.Co.,Ltd.Wakura Murata Mfg. Co., Ltd. (Peregrine Semiconductor Corp) | GRM155C80J106M | 8 | PC199,PC251,PC366,PC470,PC644,PC6546,PC6606,PC76 |
| CH6103KEA00 | CAP CHIP 10UF 16V(+-10%,X6S,0805) | MURATA ERIE N.A. INC TAIWAN BRANCH Okayama Murata Mfg.Co.,Ltd.Wakura Murata Mfg. Co., Ltd. (Peregrine Semiconductor Corp) | GRM21BC81C106K | 8 | C1076,C1077,C1170,C1331,C1333,C1340,C1767,C1768 |
| CH6103KEA01 | CAP CHIP 10UF 16V(+-10%,X6S,0805)MUR | MURATA ERIE N.A. INC TAIWAN BRANCH Okayama Murata Mfg.Co.,Ltd.Wakura Murata Mfg. Co., Ltd. (Peregrine Semiconductor Corp) | GRM21BC81C106K | 8 | PC2081,PC2082,PC2142,PC2143,PC2219,PC2220,PC2240,PC2280 |
| CH6104KEA00 | CAP CHIP 10U 25V(+-10%,X6S,0805,H1.25) | Matsuki Precision Ceramic Co., Ltd.Matsuki Polymer Technology Co., Ltd. | MAG05X6S1E106K | 51 | C142,C143,C145,C146,C147,C149,C150,C151,C153,C154,C155,C157,C158,C159,C161,C162,C163,C165,C166,C167,C169,C170,C171,C173,C174,C175,C177,C178,C179,C181,C182,C183,C1867,C1883,C5032,C509,C518,C527,C530,C531,C532,C533,C534,C535,C536,C537,C546,C547,C548,C549,C89 |
| CH6221ME900 | CAP CHIP 22U 6.3V(+-20%,X6S,0603) | ACER PERIPHERALS INC.(Darfon Electronics Corp.) Darfon Precisions(Suzhou)Co.,LTD | C1608X6S226MCT | 8 | C1920,C1921,C6030,C6042,C6046,C6066,C6079,C9922 |
| CH6222MEA01 | CAP CHIP 22U 10V(+-20%,X6S,0805)MUR | MURATA ERIE N.A. INC TAIWAN BRANCH Okayama Murata Mfg.Co.,Ltd.Wakura Murata Mfg. Co., Ltd. (Peregrine Semiconductor Corp) | GRM21BC81A226M | 5 | PC1599,PC1600,PC1855,PC1856,PC1868 |
| CH6223MEA00 | CAP CHIP 22U 16V(+-20%,X6S,0805) | MURATA ERIE N.A. INC TAIWAN BRANCH Okayama Murata Mfg.Co.,Ltd.Wakura Murata Mfg. Co., Ltd. (Peregrine Semiconductor Corp) | GRM21BC81C226M | 5 | C1213,C1829,C1830,C34,C6027 |
| CH6223MEA01 | CAP CHIP 22UF 16V(+-20%,X6S,0805)MUR | MURATA ERIE N.A. INC TAIWAN BRANCH Okayama Murata Mfg.Co.,Ltd.Wakura Murata Mfg. Co., Ltd. (Peregrine Semiconductor Corp) | GRM21BC81C226M | 233 | C1276,C1277,PC111,PC116_6,PC118_6,PC119,PC119_4,PC119_6,PC120,PC120_3,PC123,PC123_4,PC124_3,PC125_4,PC126_3,PC129,PC129_6,PC130,PC130_6,PC132_6,PC134,PC135,PC136_5,PC138_5,PC139_5,PC144_6,PC145_6,PC147_6,PC150,PC152,PC152_1,PC153_2,PC154_1,PC157_2,PC157_6,PC158_1,PC158_6,PC159_2,PC159_6,PC181_3,PC182_4,PC184_3,PC1849,PC185_4,PC1850,PC187_3,PC188_4,PC1898,PC2080,PC211_1,PC212_2,PC213_1,PC214_2,PC2141,PC215_1,PC216_2,PC218_2,PC219_1,PC2242,PC2260,PC2261,PC2262,PC2263,PC227,PC2342,PC2343,PC2344,PC254,PC264_1,PC265_2,PC266_1,PC267_2,PC268_1,PC269_2,PC27,PC294_3,PC295_4,PC296_3,PC297_4,PC298_3,PC299_4,PC311_5,PC312_5,PC313_5,PC327_1,PC328_2,PC329_1,PC330_2,PC331_1,PC332_2,PC334_1,PC335_2,PC350_3,PC351_3,PC352_3,PC353_3,PC379_1,PC380_2,PC381_1,PC382_2,PC384_1,PC385_2,PC409_4,PC410_3,PC411_4,PC412_3,PC415_4,PC416_3,PC426_5,PC427_5,PC429_5,PC442_1,PC443_2,PC444_1,PC446_2,PC448_1,PC449_2,PC483_1,PC484_2,PC485_1,PC486_2,PC487_1,PC488_2,PC513_1,PC514_2,PC515_1,PC516_2,PC517_1,PC518_2,PC521_1,PC554_3,PC555_4,PC556_3,PC557_4,PC558_3,PC559_4,PC570,PC571,PC571_5,PC572_5,PC573_5,PC576,PC587_1,PC588_2,PC589_1,PC590_2,PC591_1,PC592_2,PC593_1,PC595_2,PC60,PC6012,PC6013,PC6014,PC6015,PC61,PC610_3,PC611_3,PC612_3,PC613_3,PC626_3,PC627_4,PC628_3,PC629_4,PC632_3,PC633_4,PC6501,PC6502,PC6503,PC6504,PC6520,PC6521,PC6522,PC6523,PC6556_1,PC6557_1,PC6558_1,PC6559_1,PC6560,PC6579_2,PC6580_2,PC6581_2,PC6582_2,PC6583,PC6614_1,PC6615_1,PC6616_1,PC6617_1,PC6618,PC6635_2,PC6636_2,PC6637_2,PC6638_2,PC6639,PC6802,PC6803,PC6816,PC6817,PC6818,PC6819,PC6900,PC6901,PC6902,PC6903,PC6904,PC6905,PC7000,PC7001,PC7002,PC7003,PC8000,PC8001,PC8002,PC8003,PC8004,PC8005,PC8006,PC8007,PC8009,PC8010,PC8011,PC8012,PC8013,PC8014,PC8071,PC81,PC8567,PC89_1,PC90_2,PC91_1,PC93_2,PC95_1,PC96_2 |
| CH622KMEA03 | CAP CHIP 22U 4V(+-20%,X6S,0805)MUR | MURATA ERIE N.A. INC TAIWAN BRANCH Okayama Murata Mfg.Co.,Ltd.Wakura Murata Mfg. Co., Ltd. (Peregrine Semiconductor Corp) | GRM21BC80G226M | 116 | PC102_1,PC105_1,PC106_2,PC108_2,PC114,PC120_6,PC123_6,PC127_4,PC128_4,PC129_3,PC130_3,PC134_6,PC135_6,PC140_5,PC141_5,PC148_6,PC149_6,PC163_6,PC166_1,PC166_6,PC168_2,PC169_1,PC170_2,PC189_4,PC190_3,PC191_4,PC192_3,PC221_2,PC224_1,PC225_2,PC227_1,PC280_2,PC281_1,PC282_2,PC283_1,PC285,PC288,PC302_3,PC303_4,PC304_3,PC305_4,PC315_5,PC316_5,PC339_2,PC341_1,PC342_2,PC344_1,PC354_3,PC355_3,PC394_2,PC395_1,PC397_2,PC398_1,PC417_3,PC418_4,PC419_3,PC420_4,PC430_5,PC431_5,PC456_1,PC458_2,PC459_1,PC460_2,PC499_2,PC500_1,PC501_2,PC502_1,PC523_2,PC526_1,PC527_2,PC529_1,PC562_3,PC563_4,PC564_3,PC565_4,PC575_5,PC576_5,PC600_2,PC6018,PC602_1,PC6024,PC6025,PC6026,PC603_2,PC604_1,PC614_3,PC615_3,PC634_4,PC635_3,PC636_4,PC637_3,PC65,PC6508,PC6509,PC6510,PC6511,PC6512,PC6527,PC6528,PC6529,PC6530,PC6531,PC6566_1,PC6567_1,PC6586_2,PC6587_2,PC6624_1,PC6625_1,PC6642_2,PC6643_2,PC83,PC84,PC850,PC865,PC866,PC867 |
| CH622KMEB02 | CAP CHIP 22UF 4V(+-20%,X6S,0402) | KYOCERA CORPORATION | CM05X6S226M04AH080 | 642 | C10179,C1026,C1030,C1032,C1040,C1041,C110,C111,C115,C117,C1922,C2102,C2103,C2104,C2105,C2106,C2107,C2108,C2109,C2110,C2111,C2112,C2113,C2114,C2115,C2116,C2117,C2118,C2119,C2120,C2121,C2122,C2123,C2124,C2125,C2126,C2127,C2128,C2129,C2130,C2131,C2132,C2133,C2134,C2135,C2136,C2137,C2138,C2139,C2140,C2141,C2142,C2143,C2144,C2145,C2146,C2147,C2148,C2149,C2150,C2151,C2152,C2153,C2154,C2155,C2156,C2157,C2158,C2159,C2160,C2161,C2162,C2163,C2164,C2165,C2166,C2167,C2169,C2170,C2171,C2173,C2174,C2175,C2177,C2178,C2181,C2182,C2183,C2185,C2186,C2189,C2190,C2192,C2193,C2195,C2196,C2198,C2199,C2201,C2202,C2203,C2204,C2205,C2207,C2208,C2209,C2210,C2211,C2213,C2214,C2215,C2216,C2217,C2219,C2220,C2221,C2222,C2223,C2225,C2226,C2227,C2228,C2229,C2231,C2232,C2233,C2234,C2237,C2238,C2239,C2240,C2243,C2244,C2245,C2246,C2248,C2249,C2250,C2251,C2253,C2254,C2255,C2256,C2258,C2259,C2260,C2261,C2262,C2263,C2264,C2265,C2266,C2267,C2268,C2269,C2270,C2271,C2272,C2273,C2274,C2275,C2276,C2277,C2278,C2279,C2280,C2281,C2282,C2283,C2284,C2285,C2286,C2287,C2288,C2289,C2290,C2291,C2292,C2293,C2294,C2295,C2296,C2297,C2298,C2300,C2301,C2302,C2303,C2304,C2306,C2307,C2308,C2309,C2310,C2312,C2313,C2314,C2315,C2316,C2318,C2319,C2320,C2321,C2322,C2324,C2325,C2326,C2327,C2330,C2331,C2332,C2333,C2335,C2336,C2337,C2338,C2340,C2341,C2342,C2343,C2345,C2346,C2347,C2348,C2350,C2351,C2352,C2353,C2354,C2356,C2357,C2358,C2359,C2360,C2362,C2363,C2364,C2365,C2366,C2368,C2369,C2370,C2371,C2372,C2374,C2375,C2376,C2377,C2378,C2380,C2381,C2382,C2383,C2386,C2387,C2388,C2389,C2392,C2393,C2394,C2395,C2397,C2398,C2399,C2400,C2402,C2403,C2404,C2405,C2407,C2408,C2409,C2410,C2411,C2412,C2413,C2414,C2415,C2416,C2417,C2418,C2419,C2420,C2421,C2422,C2423,C2424,C2425,C2426,C2427,C2428,C2429,C2430,C2431,C2432,C2433,C2434,C2435,C2436,C2437,C2438,C2439,C244,C2440,C2441,C2442,C2443,C2444,C2445,C2446,C2447,C2448,C2449,C245,C2450,C2451,C2452,C2453,C2454,C2455,C2456,C2457,C2458,C2459,C246,C2460,C2461,C2462,C2463,C2464,C2465,C2466,C2467,C2468,C2469,C2470,C2471,C2472,C2473,C2474,C2475,C2476,C2477,C2478,C2479,C2480,C2481,C2482,C2483,C2484,C2485,C2486,C2487,C2488,C2489,C2490,C2491,C2492,C2493,C2494,C2495,C2496,C2497,C2498,C2499,C2500,C2501,C2502,C2503,C2504,C2505,C2506,C2507,C2508,C2509,C251,C2510,C2511,C2513,C2514,C2516,C2517,C2518,C252,C2520,C2521,C2522,C2523,C2524,C2525,C2526,C2527,C2528,C2529,C2530,C2531,C2532,C2533,C2534,C2535,C2536,C2537,C2538,C2539,C2540,C2541,C2542,C2543,C2544,C2545,C2546,C2547,C2548,C2549,C255,C2550,C2551,C2552,C2553,C2554,C2555,C2556,C2557,C2558,C2559,C2560,C2561,C2562,C2563,C2564,C2565,C2566,C2567,C2568,C2569,C2570,C2571,C2572,C2573,C2574,C2575,C2576,C2577,C2578,C2579,C2580,C2581,C2582,C2583,C2584,C2585,C2586,C2587,C2588,C2589,C259,C2590,C2591,C2592,C2593,C2594,C2595,C2596,C2597,C2598,C2599,C2600,C2601,C2602,C2603,C2604,C2605,C2606,C2607,C2608,C2609,C2610,C2611,C2612,C2613,C2614,C2615,C2616,C2617,C2618,C2619,C262,C2620,C2621,C2622,C2623,C2624,C2625,C2626,C2627,C2628,C2629,C263,C2630,C2631,C2632,C2633,C2634,C2635,C2636,C2637,C2638,C2639,C2640,C2641,C2642,C2643,C2644,C2645,C2646,C2647,C2648,C2649,C2650,C2651,C2652,C2653,C2654,C2655,C2656,C2657,C2658,C2660,C2661,C2663,C2664,C2665,C2667,C2668,C2669,C267,C2670,C2671,C2672,C2673,C268,C270,C271,C272,C273,C274,C275,C276,C277,C278,C279,C284,C318,C327,C329,C335,C351,C368,C369,C3888,C3889,C3890,C3891,C3892,C3893,C3894,C3895,C3896,C3897,C3898,C3899,C3900,C3901,C3902,C3903,C3904,C3905,C3906,C3907,C3908,C3909,C3910,C3911,C3912,C3913,C3914,C3915,C3916,C3917,C3918,C3919,C3920,C3921,C3922,C3925,C3926,C3927,C3928,C3929,C3930,C3931,C3932,C3933,C3934,C3935,C399,C402,C408,C417,C4178,C4179,C424,C434,C435,C476,C478,C486,C487,C501,C504,C505,C563,C565,C568,C575,C586,C589,C590,C630,C634,C636,C656,C663,C667,C668,C799,C805,C969,C974,C988,C992,C993 |
| CH647KMEA04 | CAP CHIP 47U 4V(+-20%,X6S,0805)MUR | MURATA ERIE N.A. INC TAIWAN BRANCH Okayama Murata Mfg.Co.,Ltd.Wakura Murata Mfg. Co., Ltd. (Peregrine Semiconductor Corp) | GRM21BC80G476M | 12 | C7002,C7003,C7006,C7007,C7033,C7034,C7035,C7036,C7038,C7039,C7040,C7041 |
| CH710KMEA01 | CAP CHIP 100U 4V(+-20%,X6S,0805)MUR | MURATA ERIE N.A. INC TAIWAN BRANCH Okayama Murata Mfg.Co.,Ltd.Wakura Murata Mfg. Co., Ltd. (Peregrine Semiconductor Corp) | GRM21BC80G107M | 64 | C102,C1022,C1025,C1028,C1029,C103,C1033,C113,C114,C220,C225,C229,C240,C247,C317,C320,C323,C324,C328,C366,C367,C398,C401,C404,C405,C409,C432,C433,C466,C471,C474,C475,C479,C502,C503,C550,C556,C559,C560,C564,C587,C588,C625,C628,C632,C633,C637,C665,C666,C7010,C7013,C7016,C7019,C7022,C7025,C7028,C7031,C795,C798,C801,C802,C966,C990,C991 |
| CH747LM8818 | CAP CHIP 470U 2.5V(+-20%,7343,SPCAP)MAT | MATSUSHITA ELECTRONICS CORPORATION (PANASONIC)Wuxi Matsushita Battery Co., Ltd (Panasonic Communication Corp. of the Phils) Panasonic Precision Devices Co.,Ltd. | EEFGX0E471R | 34 | C7000,C7001,C7004,C7005,C7008,C7009,C7011,C7012,C7014,C7015,C7017,C7018,C7020,C7021,C7023,C7024,C7026,C7027,C7029,C7030,C7032,C7037,PC534,PC6568,PC6569,PC6570,PC6626,PC6627,PC6628,PC6811,PC6812,PC6813,PC6814,PC6815 |
| CH747LM8825 | CAPCHIP 470U 2.5V(20%,SP,ESR4.5,7343)MAT | MATSUSHITA ELECTRONICS CORPORATION (PANASONIC)Wuxi Matsushita Battery Co., Ltd (Panasonic Communication Corp. of the Phils) Panasonic Precision Devices Co.,Ltd. | EEFSX0E471E4 | 14 | PC162,PC165,PC223,PC226,PC337,PC343,PC450,PC452,PC525,PC528,PC598,PC601,PC800,PC802 |
| CH-8216TB09 | CAP CHIP 8.2P 50V (+-0.1P NP0 0402) | ACER PERIPHERALS INC.(Darfon Electronics Corp.) Darfon Precisions(Suzhou)Co.,LTD | C1005NP0829BGT | 2 | C215,C216 |
| CS+001DFR10 | RES CHIP 0.001 3W +-1%(2512)RLC | RALEC ELECTRONIC CO. | LR2512-23R001F4 | 2 | R1837,R1838 |
| CS+002AFR06 | RES CHIP 0.002 2W +-1%(2512)EF | CYNTEC CO., LTD. | RL-3264-9-R002-FN | 8 | R1323,R1324,R1325,R3633,R3634,R3635,R3645,R3767 |
| CS00001JE10 | RES CHIP 0 1/20W +-5% (0201)EF | CYNTEC CO., LTD. | RR0306S-000-XTF | 375 | C1524,C1525,C1526,C1527,C1528,C1529,C1530,C1531,C1532,C1533,C1534,C1535,C1536,C1537,C1538,C1539,C1540,C1541,C1542,C1543,C1544,C1545,C1546,C1547,C48,C49,C50,C51,C52,C53,C54,C55,C710,C711,C712,C713,C714,C715,C716,C717,C718,C719,C720,C721,C722,C723,C724,C725,C726,C727,C728,C729,C730,C731,C732,C733,C734,C735,C736,C737,C738,C739,C740,C741,C742,C743,C744,C745,C746,C747,C748,C749,C750,C751,C752,C753,C754,C755,C756,C757,C758,C759,C760,C761,C762,C763,C764,C765,C766,C767,C768,C769,C770,C771,C772,C773,C806,C807,C808,C809,C810,C811,C812,C813,C814,C815,C816,C817,C818,C819,C820,C821,C822,C823,C824,C825,C826,C827,C828,C829,C830,C831,C832,C833,C834,C835,C836,C837,C838,C839,C840,C841,C842,C843,C844,C845,C846,C847,C848,C849,C850,C851,C852,C853,C854,C855,C856,C857,C858,C859,C860,C861,C862,C863,C864,C865,C866,C867,C868,C869,C870,C871,C872,C873,C874,C875,C876,C877,C878,C879,C880,C881,C882,C883,C884,C885,C886,C887,C888,C889,C890,C891,C892,C893,C894,C895,C896,C897,C898,C899,C900,C901,C902,C903,C904,C905,C906,C907,C908,C909,C910,C911,C912,C913,C914,C915,C916,C917,C918,C919,C920,C921,C922,C923,C924,C925,C926,C927,C928,C929,C930,C931,C932,C933,C934,C935,C936,C937,C938,C939,C940,C941,C942,C943,C944,C945,C946,C947,C948,C949,C950,C951,C952,C953,C954,C955,C956,C957,C958,C959,C960,C961,C962,C963,C964,C965,R1004,R1012,R1025,R1026,R1042,R1043,R1047,R1054,R1067,R1068,R1083,R1084,R1088,R1096,R1109,R1110,R1125,R1126,R1198,R1199,R1200,R1201,R1206,R1209,R1210,R1211,R1514,R1515,R595,R596,R597,R598,R599,R609,R611,R612,R613,R614,R615,R6152,R6153,R6156,R6157,R616,R619,R6190,R6191,R6194,R6195,R620,R621,R622,R6708,R6709,R6732,R6733,R6736,R6737,R6746,R6747,R6748,R6749,R6754,R6755,R6756,R6757,R6758,R6759,R6760,R6761,R6776,R6796,R6797,R6810,R6811,R6812,R6813,R6820,R6821,R6902,R6903,R697,R709,R711,R731,R732,R779,R780,R797,R799,R801,R802,R803,R805,R806,R807,R808,R809,R828,R829,R830,R831,R832,R833,R848,R850,R851,R854,R860,R872,R873,R895,R901,R913,R914,R953,R963,R976,R977 |
| CS00002JB13 | RES CHIP 0 1/16W +-5%(0402)EF | CYNTEC CO., LTD. | RR0510S-000-XTF | 817 | PR103,PR104,PR111,PR112,PR12,PR121,PR125,PR13,PR137,PR138,PR14,PR150,PR169,PR170,PR172,PR173,PR174,PR181,PR191,PR192,PR199,PR200,PR204,PR211,PR212,PR2149,PR216,PR217,PR236,PR237,PR239,PR245,PR246,PR251,PR260,PR261,PR268,PR269,PR273,PR280,PR281,PR283,PR3002,PR302,PR303,PR305,PR306,PR307,PR314,PR32,PR324,PR325,PR33,PR332,PR333,PR3337,PR335,PR34,PR340,PR35,PR350,PR351,PR355,PR36,PR362,PR363,PR367,PR37,PR374,PR375,PR384,PR387,PR388,PR3910,PR3911,PR3916,PR3917,PR3919,PR3920,PR3921,PR3922,PR3928,PR3930,PR397,PR398,PR3980,PR3981,PR3988,PR3989,PR3992,PR3993,PR3994,PR3995,PR40,PR401,PR4012,PR406,PR407,PR408,PR409,PR411,PR412,PR415,PR417,PR419,PR421,PR425,PR429,PR433,PR435,PR436,PR437,PR440,PR441,PR442,PR445,PR477,PR530,PR531,PR532,PR533,PR59,PR60,PR6000,PR62,PR6500,PR6501,PR6520,PR6521,PR6531,PR6539,PR6540,PR6541,PR6542,PR6543,PR6544,PR6548,PR6550,PR6556,PR6564,PR6601,PR6603,PR6605,PR6606,PR6609,PR6610,PR6611,PR6612,PR6613,PR6614,PR6616,PR6618,PR6619,PR6626,PR6631,PR68,PR6809,PR6810,PR6811,PR6816,PR6819,PR6820,PR6821,PR69,PR74,PR8000,PR8005,PR8006,PR8007,PR8008,PR8009,PR8010,PR8011,PR8012,PR83,PR832,PR835,PR84,PR91,PR92,PR96,R1036,R1038,R1129,R1132,R1134,R1139,R1142,R1143,R1148,R1153,R1154,R1159,R1160,R1161,R1162,R1163,R1166,R1168,R1169,R1170,R1179,R118,R1181,R119,R1191,R1202,R1204,R1205,R121,R122,R123,R1243,R1244,R125,R1251,R1252,R1254,R1255,R1256,R1257,R1259,R1263,R1269,R1270,R1271,R1272,R1273,R1274,R1275,R1276,R1277,R1293,R1294,R1295,R1296,R1297,R1298,R1299,R13,R1300,R1312,R1315,R132,R1329,R133,R1339,R1340,R1350,R1352,R1353,R1354,R1355,R1359,R1360,R137,R14,R141,R1423,R1425,R1447,R1453,R1486,R149,R15,R1500,R1509,R151,R1518,R1520,R1522,R1523,R1524,R1526,R153,R1533,R156,R157,R1571,R1619,R162,R1625,R1633,R1634,R1648,R1651,R167,R1671,R168,R1714,R1736,R1737,R1738,R1739,R175,R1798,R180,R1801,R181,R1815,R1816,R182,R183,R184,R185,R187,R188,R189,R1895,R190,R193,R194,R196,R197,R198,R202,R203,R204,R205,R206,R209,R210,R211,R2113,R2114,R213,R222,R223,R226,R2268,R228,R230,R231,R2316,R2318,R233,R234,R235,R236,R237,R238,R239,R241,R242,R243,R244,R245,R246,R2473,R250,R251,R252,R2529,R253,R2531,R254,R255,R2565,R2566,R258,R2586,R260,R261,R262,R263,R264,R2659,R2660,R2676,R268,R269,R27,R2703,R2704,R2706,R2707,R271,R2725,R274,R278,R2786,R2787,R2793,R2796,R28,R280,R2802,R2803,R281,R283,R284,R2848,R286,R2899,R29,R2905,R2906,R2922,R2967,R2968,R2982,R2983,R2992,R30,R3033,R3047,R3048,R3063,R3105,R3106,R3107,R3108,R3109,R3110,R3111,R3142,R3144,R3168,R3169,R3170,R3171,R3172,R3177,R3178,R3180,R3194,R3195,R3196,R3197,R3198,R3199,R3200,R3201,R3205,R321,R3233,R3236,R3237,R3244,R325,R326,R327,R328,R3294,R3303,R3304,R3305,R3306,R3307,R3308,R3326,R3327,R333,R3335,R3336,R3337,R3338,R3352,R3353,R3354,R3355,R337,R338,R3393,R3394,R3441,R3442,R3443,R3499,R3516,R3517,R3518,R3526,R3527,R3559,R356,R3560,R3561,R3563,R3568,R3569,R357,R3572,R3573,R3576,R3577,R3580,R3581,R3600,R3601,R3620,R364,R3651,R3652,R3655,R3662,R3666,R3671,R3672,R3680,R3682,R3684,R3686,R3688,R3710,R3713,R3714,R3715,R3716,R3717,R3718,R3719,R3720,R3721,R3722,R374,R3751,R3752,R3754,R3756,R3770,R3772,R3775,R3776,R3777,R3778,R3779,R3784,R3785,R38,R3807,R3827,R3831,R3861,R3865,R3868,R3870,R39,R3924,R3941,R395,R3958,R3959,R3972,R3973,R3975,R3996,R3997,R40,R404,R405,R4062,R4063,R4064,R407,R4075,R4076,R4087,R41,R419,R42,R4212,R4213,R4214,R4215,R426,R4268,R427,R428,R429,R430,R4303,R4304,R4305,R4306,R431,R435,R436,R439,R4450,R4501,R4535,R4536,R4537,R46,R4601,R4602,R473,R474,R4809,R481,R482,R483,R484,R485,R486,R487,R493,R494,R5052,R5054,R5099,R51,R5234,R5236,R529,R530,R5377,R56,R561,R564,R565,R566,R567,R57,R570,R573,R576,R589,R600,R6000,R6001,R6002,R6003,R6004,R6005,R6006,R6007,R6008,R6009,R6010,R6011,R6012,R6013,R6014,R6015,R6025,R6026,R6028,R603,R6032,R6033,R6038,R6039,R6047,R6048,R6051,R6052,R6053,R6054,R6055,R6056,R6057,R6058,R6059,R606,R6067,R6069,R607,R6073,R6074,R6075,R6078,R6092,R6093,R6095,R6096,R6097,R6099,R6101,R6102,R6103,R6104,R6105,R6108,R6109,R6110,R6111,R6116,R6118,R6119,R618,R6183,R6184,R6200,R6201,R6228,R6229,R6240,R6241,R6242,R6245,R6254,R646,R647,R650,R6500,R651,R657,R658,R661,R662,R6710,R6711,R6740,R6741,R6777,R6781,R6784,R6785,R6792,R6793,R6798,R6799,R6800,R6801,R6804,R6805,R6806,R6807,R6823,R6824,R6825,R6826,R6852,R6853,R6858,R6859,R70,R734,R74,R744,R75,R76,R8004,R8018,R8021,R8030,R8032,R8034,R8047,R8058,R8064,R8071,R8072,R8080,R8081,R8083,R8084,R8086,R8087,R8089,R8090,R8094,R8097,R8101,R8102,R8168,R817,R8176,R8179,R818,R819,R8224,R8235,R8241,R8248,R8249,R8282,R8301,R8305,R8306,R8308,R8309,R8312,R8350,R8351,R8381,R8382,R8385,R8386,R85,R856,R8563,R8564,R8565,R8566,R86,R862,R877,R899,R9,R9001,R9010,R9011,R9012,R9013,R9018,R9019,R905,R9273,R9274,R9275,R9276,R928,R929,R930,R931,R932,R934,R935,R936,R937,R939,R940,R955,R956 |
| CS00006J900 | RES CHIP 0 1/4W +-5%(0603) | EVER OHMS TECHNOLOGY CO., LTD. | MRE060301JR000CZ | 8 | R1011,R1053,R1095,R6705,R712,R859,R900,R962 |
| CS01002FB07 | RES CHIP 10 1/16W +-1%(0402)EF | CYNTEC CO., LTD. | RR0510S-100-FTF | 49 | PR3782,PR3792,PR3798,PR3830,PR3966,PR3967,PR400,PR4003,PR434,R1283,R1284,R1291,R1292,R1301,R1302,R1674,R1675,R1676,R1677,R1678,R1679,R1680,R1681,R1683,R1684,R1685,R1686,R1687,R1696,R1697,R1699,R1701,R1704,R1705,R1707,R1708,R1709,R1710,R1711,R3570,R3571,R3574,R3575,R3578,R3579,R3602,R3603,R3758,R3760 |
| CS01502FB03 | RES CHIP 15 1/16W +-1%(0402)EF | CYNTEC CO., LTD. | RR0510S-150-FTF | 24 | R375,R376,R377,R378,R379,R380,R381,R382,R383,R384,R385,R386,R500,R501,R502,R503,R504,R505,R506,R507,R508,R509,R510,R511 |
| CS02201FE11 | RES CHIP 22 1/20W +-1%(0201)EF | YAGEO CORPORATION | RC0201FR-0722RP | 2 | R674,R695 |
| CS02202FB02 | RES CHIP 22 1/16W +-1%(0402)EF | CYNTEC CO., LTD. | RR0510S-220-FTF | 19 | R1635,R1636,R1638,R1639,R1640,R1641,R1642,R1643,R1644,R1645,R1740,R1741,R1742,R1743,R2588,R3934,R59,R72,R73 |
| CS02702JB02 | RES CHIP 27 1/16W +-5%(0402)EF | WALSIN TECHNOLOGY CORPORATION | WR04X270 JTR | 1 | R2674 |
| CS02742FB03 | RES CHIP 27.4 1/16W +-1%(0402)EF | CYNTEC CO., LTD. | RR0510S-27R4-FTF | 3 | R1140,R1141,R3181 |
| CS03302JB10 | RES CHIP 33 1/16W +-5%(0402)EF | CYNTEC CO., LTD. | RR0510S-330-JTF | 173 | R1005,R116,R120,R1203,R1253,R1278,R1279,R1280,R1281,R1282,R1311,R1321,R1362,R1363,R1458,R1459,R1494,R1495,R1496,R1497,R1498,R152,R1528,R1549,R1550,R1551,R1552,R1553,R1556,R1557,R1558,R1563,R1564,R158,R159,R1592,R1593,R160,R161,R1616,R1620,R163,R1631,R1632,R164,R165,R166,R169,R170,R171,R172,R173,R174,R176,R177,R179,R186,R195,R199,R208,R212,R214,R215,R216,R217,R218,R219,R220,R221,R224,R225,R227,R229,R23,R232,R247,R248,R249,R259,R265,R266,R267,R270,R273,R275,R277,R279,R282,R285,R289,R308,R309,R349,R350,R351,R352,R371,R372,R434,R459,R460,R461,R463,R464,R466,R467,R468,R469,R470,R471,R475,R476,R477,R478,R488,R489,R49,R497,R50,R58,R588,R602,R6029,R6030,R6031,R6063,R6076,R6077,R608,R63,R645,R648,R6506,R6782,R6783,R685,R6850,R6851,R6854,R6855,R6856,R6857,R6862,R6863,R6864,R6865,R708,R71,R738,R798,R8005,R8006,R8007,R8008,R8057,R8066,R8073,R81,R8166,R8177,R8178,R8234,R8243,R8250,R8299,R8310,R8311,R8383,R933,R957,R958,R959,R992 |
| CS03321FE09 | RES CHIP 33.2 1/20W +-1%(0201)EF | CYNTEC CO., LTD. | RR0306S-33R2-FTF | 17 | R668,R669,R672,R673,R6779,R678,R6780,R679,R682,R683,R687,R688,R689,R690,R693,R694,R698 |
| CS03322FB03 | RES CHIP 33.2 1/16W +-1%(0402)EF | CYNTEC CO., LTD. | RR0510S-33R2-FTF | 156 | R11667,R1173,R1174,R1175,R1177,R1178,R1344,R1345,R1346,R1347,R1348,R1349,R1516,R1517,R1594,R1595,R1719,R2,R2261,R2262,R2410,R2411,R2413,R2414,R2415,R2416,R2417,R2418,R2419,R2420,R2421,R2422,R2423,R2424,R2425,R2489,R2663,R2664,R2671,R2672,R2675,R2811,R2812,R2844,R2845,R2846,R2847,R2897,R2898,R2939,R2944,R2990,R2991,R2995,R2996,R3036,R3066,R3112,R3113,R3114,R3185,R3191,R3193,R3203,R3231,R3234,R3238,R3239,R3301,R3315,R3324,R3340,R3341,R3397,R347,R3476,R3477,R3478,R3479,R348,R3480,R3481,R3482,R3483,R3484,R3485,R3486,R3496,R3497,R3505,R3533,R3534,R3553,R3554,R3586,R3587,R3588,R3589,R3590,R3591,R3592,R3593,R3594,R3595,R3654,R3711,R3712,R3858,R3909,R4143,R4144,R4145,R4146,R4147,R4148,R4149,R4150,R4151,R4152,R4157,R4170,R4171,R4172,R4178,R4179,R4180,R4181,R4182,R4183,R4266,R4451,R4506,R4507,R4508,R4509,R4556,R4557,R4558,R4563,R4608,R55,R604,R6112,R6113,R6252,R6253,R65,R8000,R8118,R8124,R9022,R9023,R9031,R9033,R9034,R9446 |
| CS04991FE06 | RES CHIP 49.9 1/20W +-1%(0201)EF | CYNTEC CO., LTD. | RR0306S-49R9-FTF | 14 | R666,R667,R670,R671,R675,R676,R677,R680,R681,R684,R686,R691,R692,R696 |
| CS04992FB07 | RES CHIP 49.9 1/16W +-1%(0402)EF | CYNTEC CO., LTD. | RR0510S-49R9-FTF | 73 | PR114,PR115,PR161,PR162,PR163,PR164,PR226,PR227,PR228,PR229,PR288,PR294,PR295,PR296,PR297,PR399,PR402,PR418,PR438,PR460,PR49,PR50,PR51,PR52,PR6530,PR6532,PR6600,PR6602,R1,R1568,R1569,R1570,R1572,R1573,R1574,R1575,R1576,R1577,R1578,R1579,R1580,R1581,R1582,R1583,R1584,R1585,R1586,R1587,R1588,R1589,R1590,R1591,R2917,R2924,R2925,R315,R3390,R3391,R3392,R3468,R3469,R3515,R4550,R465,R5102,R5103,R605,R61,R6100,R8171,R8182,R8238,R8304 |
| CS-1002FB04 | RES CHIP 1 1/16W +-1%(0402)EF | CYNTEC CO., LTD. | RR0510S-1R0-FTF | 10 | PR130,PR183,PR253,PR316,PR393,PR6538,PR6608,PR76,PR8389,R4077 |
| CS-1003F900 | RES CHIP 1 1/10W +-1%(0603)EF | RALEC ELECTRONIC CO. | FTT031R00FTP | 4 | R4475,R4493,R555,R586 |
| CS11002FB07 | RES CHIP 100 1/16W +-1%(0402)EF | CYNTEC CO., LTD. | RR0510S-101-FTF | 16 | R1422,R1508,R1779,R1856,R1896,R1897,R1898,R22,R240,R3208,R3216,R3217,R5071,R6046,R6117,R8063 |
| CS11302FB03 | RES CHIP 130 1/16W +-1%(0402)EF | CYNTEC CO., LTD. | RR0510S-131-FTF | 21 | R1444,R3069,R3071,R3074,R3075,R3086,R3087,R3088,R3089,R3090,R3091,R3092,R3093,R3094,R3095,R3096,R3097,R3099,R3100,R6246,R948 |
| CS12001FE12 | RES CHIP 200 1/20W +-1%(0201)EF | CYNTEC CO., LTD. | RR0306S-201-FTF | 16 | R1022,R1041,R1064,R1082,R1106,R1124,R6723,R6731,R6795,R6809,R6901,R701,R756,R869,R910,R973 |
| CS12002FB06 | RES CHIP 200 1/16W +-1%(0402)EF | CYNTEC CO., LTD. | RR0510S-201-FTF | 7 | R1194,R1266,R3228,R3229,R47,R48,R6202 |
| CS12436F201 | RES CHIP 243 1/4W +-1%(1206)EF | WALSIN TECHNOLOGY CORPORATION | WR12X2430FTR | 4 | R4638,R4639,R4640,R4641 |
| CS12492FB02 | RES CHIP 249 1/16W +-1%(0402)EF | CYNTEC CO., LTD. | RR0510S-2490-FTF | 2 | R8029,R950 |
| CS14702FB04 | RES CHIP 470 1/16W +-1%(0402)EF | KOASPEER ELECTRONICS INC. | RK73H1EVTTP4700F | 3 | R1207,R1208,R3102 |
| CS14993F901 | RES CHIP 499 1/10W +-1%(0603)EF | EVER OHMS TECHNOLOGY CO., LTD. | CRG0603F499RP05Z | 2 | PR6557,PR6625 |
| CS15602FB03 | RES CHIP 560 1/16W +-1%(0402)EF | WALSIN TECHNOLOGY CORPORATION | WR04X5600FTR | 6 | R8022,R8023,R8024,R8025,R8026,R8027 |
| CS16802FB03 | RES CHIP 680 1/16W +-1%(0402)EF | CYNTEC CO., LTD. | RR0510S-681-FTF | 1 | R3653 |
| CS16812FB02 | RES CHIP 681 1/16W +-1%(0402)EF | CYNTEC CO., LTD. | RR0510S-6810-FTF | 1 | PR292 |
| CS18452FB01 | RES CHIP 845 1/16W +-1%(0402)EF | CYNTEC CO., LTD. | RR0510S-8450-FTF | 2 | PR3781,PR3823 |
| CS21001FE07 | RES CHIP 1K 1/20W +-1%(0201)EF | CYNTEC CO., LTD. | RR0306S-102-FTF | 88 | R1013,R1018,R1044,R1055,R1060,R1085,R1097,R1102,R1127,R1212,R1213,R1214,R1215,R1216,R1217,R1218,R1219,R1364,R1372,R1380,R1391,R1400,R1408,R1410,R1411,R1415,R1416,R1418,R1420,R1428,R1429,R1431,R1432,R1436,R1437,R1448,R1451,R1462,R1463,R1468,R1469,R6706,R6707,R6712,R6717,R6718,R6719,R6734,R6735,R6738,R6739,R6750,R6751,R6752,R6753,R6762,R6763,R6764,R6765,R6766,R6767,R6768,R6769,R6788,R6789,R6790,R6791,R6822,R735,R796,R810,R812,R826,R827,R834,R835,R836,R837,R838,R839,R840,R841,R861,R892,R902,R949,R964,R969 |
| CS21002FB06 | RES CHIP 1K 1/16W +-1%(0402)EF | CYNTEC CO., LTD. | RR0510S-102-FTF | 226 | PR152,PR232,PR285,PR334,PR337,PR339,PR342,PR378,PR395,PR403,PR410,PR414,PR439,PR444,PR447,PR55,PR6615,PR6812,PR8073,PR836,R10296,R1128,R1131,R1133,R1144,R1149,R1165,R1167,R117,R1171,R1183,R1184,R1185,R1186,R1187,R1188,R1189,R1190,R1192,R1240,R1242,R1303,R1507,R1527,R1546,R1605,R1621,R1624,R1626,R1627,R1628,R1629,R1630,R1646,R1647,R1649,R1650,R1654,R1775,R1776,R1777,R178,R1854,R1905,R1906,R1907,R1908,R2587,R2694,R2696,R291,R292,R293,R294,R295,R2950,R296,R297,R298,R299,R300,R301,R302,R303,R304,R305,R306,R307,R310,R311,R312,R313,R3133,R3134,R3135,R3136,R314,R3147,R317,R3173,R3176,R319,R3278,R3284,R3322,R3454,R3459,R3470,R3488,R3490,R359,R360,R362,R363,R366,R3668,R367,R3670,R369,R370,R3704,R3707,R3709,R3925,R398,R399,R400,R401,R402,R403,R4090,R4091,R4092,R4093,R4094,R4185,R4187,R4189,R4191,R4193,R4195,R4197,R4199,R4201,R4203,R4205,R4207,R44,R442,R443,R4521,R4543,R4605,R523,R524,R525,R526,R527,R528,R54,R569,R587,R601,R6034,R6120,R6126,R6127,R6128,R6129,R6130,R6134,R6135,R6136,R6142,R6143,R6144,R6145,R6146,R6150,R6151,R62,R6223,R638,R639,R652,R655,R659,R663,R665,R6744,R6745,R6786,R6787,R6860,R6861,R710,R714,R718,R747,R8033,R8056,R8065,R8070,R8075,R8106,R811,R8119,R8125,R8165,R8167,R8180,R8184,R8233,R8242,R8247,R8252,R8298,R8300,R8313,R8317,R8380,R8420,R8423,R87,R9000,R993 |
| CS21212FB05 | RES CHIP 1.21K 1/16W +-1%(0402)EF | KOASPEER ELECTRONICS INC. | RK73H1EVTTP1211F | 1 | R1800 |
| CS21332FB05 | RES CHIP 1.33K 1/16W +-1%(0402)EF | RALEC ELECTRONIC CO. | FTT021331FTH | 1 | PR4008 |
| CS21962FB05 | RES CHIP 1.96K 1/16W +-1%(0402)EF | RALEC ELECTRONIC CO. | FTT021961FTH | 1 | PR67 |
| CS22002BB07 | RES CHIP 2K 1/16W +-0.1%(0402)EF | EVER OHMS TECHNOLOGY CO., LTD. | CRG0402B2K00Q10Z | 10 | PR1101,PR1131,PR1133,PR3914,PR3915,PR3918,PR3986,PR3987,PR3990,PR3991 |
| CS22002FB07 | RES CHIP 2K 1/16W +-1%(0402)EF | CYNTEC CO., LTD. | RR0510S-202-FTF | 5 | R1230,R2900,R3,R6114,R6115 |
| CS-2202FB01 | RES CHIP 2.2 1/16W +-1%(0402)EF | CYNTEC CO., LTD. | RR0510S-2R2-FTF | 48 | PR100,PR107,PR108,PR131,PR132,PR185,PR186,PR193,PR194,PR201,PR205,PR206,PR213,PR256,PR257,PR264,PR265,PR271,PR276,PR277,PR318,PR319,PR326,PR327,PR344,PR345,PR352,PR356,PR357,PR364,PR370,PR371,PR416,PR422,PR427,PR430,PR6800,PR6801,PR79,PR80,PR8001,PR8002,PR8003,PR8004,PR87,PR88,PR94,PR99 |
| CS-2202JB25 | RES CHIP 2.2 1/16W +-5% (0402) | CYNTEC CO., LTD. | RR0510S-2R2-JN | 4 | PR6552,PR6560,PR6621,PR6627 |
| CS22202JB07 | RES CHIP 2.2K 1/16W +-5%(0402)EF | CYNTEC CO., LTD. | RR0510S-222-JTF | 82 | R1089,R1090,R1316,R1341,R1351,R1357,R1424,R207,R2667,R2669,R2984,R2985,R3395,R3396,R3535,R3536,R3582,R3583,R3723,R3724,R3725,R3726,R3727,R3728,R3729,R3730,R3731,R3732,R387,R388,R389,R390,R391,R393,R394,R396,R397,R408,R409,R410,R411,R412,R413,R414,R415,R416,R417,R418,R422,R424,R437,R441,R498,R512,R513,R514,R515,R516,R517,R518,R520,R521,R522,R531,R532,R533,R534,R535,R537,R538,R539,R540,R559,R562,R6211,R6212,R632,R633,R6502,R6503,R66,R67 |
| CS22492FB05 | RES CHIP 2.49K 1/16W +-1%(0402)EF | CYNTEC CO., LTD. | RR0510S-2491-FTF | 1 | PR3969 |
| CS22672FB03 | RES CHIP 2.67K 1/16W +-1%(0402)EF | CYNTEC CO., LTD. | RR0510S-2671-FTF | 1 | PR3970 |
| CS23092FB04 | RES CHIP 3.09K 1/16W +-1%(0402)EF | CYNTEC CO., LTD. | RR0510S-3091-FTF | 1 | PR126 |
| CS24532FB03 | RES CHIP 4.53K 1/16W +-1%(0402)EF | CYNTEC CO., LTD. | RR0510S-4531-FTF | 2 | PR3824,PR5481 |
| CS24701JE04 | RES CHIP 4.7K 1/20W +-5%(0201)EF | CYNTEC CO., LTD. | RR0306S-472-JTF | 78 | R1031,R1033,R1035,R1037,R1039,R1074,R1076,R1078,R1079,R1080,R1115,R1118,R1120,R1121,R1122,R1361,R1365,R1366,R1367,R1368,R1371,R1373,R1374,R1375,R1376,R1379,R1381,R1382,R1383,R1387,R1390,R1392,R1393,R1394,R1395,R1399,R1401,R1402,R1403,R1404,R1407,R1409,R1412,R1417,R1421,R1430,R1433,R6773,R6774,R6775,R719,R723,R725,R726,R727,R785,R787,R791,R792,R793,R845,R846,R847,R879,R881,R883,R884,R885,R919,R921,R923,R924,R925,R982,R984,R995,R997,R998 |
| CS24702FB06 | RES CHIP 4.7K 1/16W +-1%(0402)EF | CYNTEC CO., LTD. | RR0510S-472-FTF | 30 | R1224,R1308,R1320,R1322,R1785,R2488,R2843,R3162,R3167,R3184,R3190,R32,R3266,R3292,R3295,R3296,R34,R3608,R3611,R3616,R3622,R3623,R3624,R3627,R3763,R3936,R4568,R53,R6247,R6250 |
| CS24702JB10 | RES CHIP 4.7K 1/16W +-5%(0402)EF | CYNTEC CO., LTD. | RR0510S-472-JTF | 115 | R1000,R1285,R1286,R1287,R1288,R1313,R1318,R1338,R1356,R1419,R1547,R1567,R1622,R1637,R1658,R1702,R1703,R1729,R2121,R2125,R2344,R2530,R276,R2794,R2834,R2835,R2836,R2841,R2842,R2909,R2915,R2918,R2926,R2932,R2937,R3029,R3034,R3320,R3432,R3433,R3434,R3435,R3474,R3500,R3501,R3503,R3519,R3520,R3530,R3532,R4073,R4125,R4126,R4127,R4137,R4138,R4139,R4155,R4164,R4165,R4166,R4264,R444,R445,R446,R447,R450,R451,R452,R4545,R4553,R4560,R4604,R492,R495,R499,R544,R545,R546,R547,R550,R551,R552,R553,R590,R6049,R6081,R6082,R6083,R6084,R6090,R617,R6181,R6182,R654,R8002,R8003,R8028,R9004,R9005,R9008,R9009,R9016,R9017,R9026,R9043,R938,R942,R943,R944,R945,R946,R947,R996,R999 |
| CS24752FB03 | RES CHIP 4.75K 1/16W +-1%(0402)EF | CYNTEC CO., LTD. | RR0510S-4751-FTF | 2 | R4489,R579 |
| CS24992BB04 | RES CHIP 4.99K 1/16W +-0.1%(0402)EF | WALSIN TECHNOLOGY CORPORATION | WF04H4991BTR | 2 | PR3927,PR3932 |
| CS25112FB04 | RES CHIP 5.11K 1/16W +-1%(0402)EF | CYNTEC CO., LTD. | RR0510S-5111-FTF | 12 | R1231,R1232,R1233,R1234,R1235,R1236,R1237,R2907,R2908,R4567,R8115,R8122 |
| CS25232FB08 | RES CHIP 5.23K 1/16W +-1%(0402)EF | YAGEO CORPORATION | RC0402FR-075K23P | 1 | PR159 |
| CS25362FB02 | RES CHIP 5.36K 1/16W +-1%(0402)EF | CYNTEC CO., LTD. | RR0510S-5361-FTF | 2 | PR3780,PR3822 |
| CS26042FB04 | RES CHIP 6.04K 1/16W +-1%(0402)EF | CYNTEC CO., LTD. | RR0510S-6041-FTF | 1 | R6203 |
| CS26192FB03 | RES CHIP 6.19K 1/16W +-1%(0402)EF | CYNTEC CO., LTD. | RR0510S-6191-FTF | 1 | R1117 |
| CS26802FB02 | RES CHIP 6.8K 1/16W +-1%(0402)EF | CYNTEC CO., LTD. | RR0510S-682-FTF | 4 | PR3787,PR3806,PR3961,PR4001 |
| CS26982FB08 | RES CHIP 6.98K 1/16W +-1%(0402)EF | RALEC ELECTRONIC CO. | FTT026981FTH | 1 | PR452 |
| CS27152FB03 | RES CHIP 7.15K 1/16W +-1%(0402)EF | CYNTEC CO., LTD. | RR0510S-7151-FTF | 5 | PR3790,PR3829,PR3964,PR6502,PR6522 |
| CS27872FB02 | RES CHIP 7.87K 1/16W +-1%(0402)EF | CYNTEC CO., LTD. | RR0510S-7871-FTF | 1 | R1799 |
| CS28662FB02 | RES CHIP 8.66K 1/16W +-1%(0402)EF | CYNTEC CO., LTD. | RR0510S-8661-FTF | 2 | PR448,PR8 |
| CS29092FB05 | RES CHIP 9.09K 1/16W +-1%(0402)EF | CYNTEC CO., LTD. | RR0510S-9091-FTF | 2 | R1226,R1791 |
| CS29312FB02 | RES CHIP 9.31K 1/16W +-1%(0402)EF | CYNTEC CO., LTD. | RR0510S-9311-FTF | 1 | PR3968 |
| CS29532FB06 | RES CHIP 9.53K 1/16W +-1%(0402)EF | RALEC ELECTRONIC CO. | FTT029531FTH | 1 | PR244 |
| CS29762FB05 | RES CHIP 9.76K 1/16W +-1%(0402)EF | CYNTEC CO., LTD. | RR0510S-9761-FTF | 1 | PR3971 |
| CS31001FE17 | RES CHIP 10K 1/20W +-1%(0201)EF | CYNTEC CO., LTD. | RR0306S-103-FTF | 42 | R1019,R1020,R1028,R1029,R1061,R1062,R1070,R1072,R1103,R1104,R1112,R1113,R1370,R1378,R1389,R1398,R1406,R1414,R1427,R1435,R6720,R6721,R6778,R707,R715,R749,R752,R782,R783,R849,R866,R867,R875,R876,R907,R908,R916,R917,R970,R971,R979,R980 |
| CS31002FB08 | RES CHIP 10K 1/16W +-1%(0402)EF | CYNTEC CO., LTD. | RR0510S-103-FTF | 140 | PR147,PR2106,PR231,PR3,PR3935,PR4,PR470,PR5,PR54,PR6,PR6003,PR6008,PR6010,PR6011,PR6507,PR6526,R10,R1009,R10287,R11,R1138,R1150,R1176,R12,R126,R1304,R1342,R1396,R16,R1673,R17,R1734,R1744,R1745,R1746,R1747,R18,R1822,R1824,R1857,R19,R1929,R1930,R20,R2317,R2356,R25,R2666,R3164,R3165,R3174,R3175,R3182,R3183,R3297,R3298,R335,R3455,R3457,R3465,R3466,R3467,R3487,R35,R3507,R3509,R3529,R36,R3660,R3663,R37,R3771,R4058,R4065,R4067,R4068,R4070,R4071,R4072,R4074,R4079,R4080,R4081,R4121,R4135,R4153,R4476,R4491,R4492,R45,R4518,R4519,R4520,R4603,R479,R5004,R560,R568,R577,R580,R585,R592,R593,R594,R6085,R6185,R6204,R6205,R6206,R6207,R6208,R6209,R6213,R6215,R6219,R6221,R6222,R6243,R6244,R6504,R6802,R6803,R69,R7,R721,R800,R8037,R8038,R8039,R804,R8040,R8113,R8120,R8421,R8422,R9002,R9006,R9014,R9032,R994 |
| CS31002JB08 | RES CHIP 10K 1/16W +-5%(0402)EF | CYNTEC CO., LTD. | RR0510S-103-JTF | 35 | R1261,R1262,R1265,R131,R1449,R1450,R1452,R1457,R1492,R1493,R1502,R453,R454,R5055,R5101,R6040,R6042,R6044,R6106,R6107,R644,R6505,R730,R737,R743,R751,R753,R760,R8009,R813,R816,R821,R822,R824,R8465 |
| CS31152FB03 | RES CHIP 11.5K 1/16W +-1%(0402)EF | CYNTEC CO., LTD. | RR0510S-1152-FTF | 1 | PR6004 |
| CS31182BB06 | RES CHIP 11.8K 1/16W +-0.1%(0402)EF | TA-I TECHNOLOGY CO.,LTD. | RB04BTP1182 | 1 | PR8091 |
| CS31242FB02 | RES CHIP 12.4K 1/16W +-1%(0402)EF | CYNTEC CO., LTD. | RR0510S-1242-FTF | 1 | PR454 |
| CS31372FB03 | RES CHIP 13.7K 1/16W +-1%(0402)EF | KOASPEER ELECTRONICS INC. | RK73H1EVTTP1372F | 1 | PR464 |
| CS31502BB03 | RES CHIP 15K 1/16W +-0.1%(0402)EF | KOASPEER ELECTRONICS INC. | RN731ETQTP1502B25 | 1 | PR830 |
| CS31502FB05 | RES CHIP 15K 1/16W +-1%(0402)EF | CYNTEC CO., LTD. | RR0510S-153-FTF | 7 | PR3788,PR3791,PR3812,PR3828,PR3962,PR3965,PR4002 |
| CS31542FB02 | RES CHIP 15.4K 1/16W +-1%(0402)EF | CYNTEC CO., LTD. | RR0510S-1542-FTF | 4 | R761,R765,R770,R774 |
| CS31692FB03 | RES CHIP 16.9K 1/16W +-1%(0402)EF | CYNTEC CO., LTD. | RR0510S-1692-FTF | 4 | PR8089,R1441,R1443,R3933 |
| CS31782FB04 | RES CHIP 17.8K 1/16W +- 1% (0402)EF | RALEC ELECTRONIC CO. | FTT021782FTH | 3 | PR4004,R8114,R8121 |
| CS31802FB04 | RES CHIP 18K 1/16W +-1%(0402)EF | WALSIN TECHNOLOGY CORPORATION | WR04X1802FTR | 8 | R1220,R1221,R1222,R1223,R1225,R1229,R1238,R3005 |
| CS32001FE00 | RES CHIP 20K 1/20W +-1%(0201) | YAGEO CORPORATION | RC0201FR-0720KL | 8 | R1016,R1058,R1100,R6715,R746,R865,R906,R967 |
| CS32002FB06 | RES CHIP 20K 1/16W +-1%(0402)EF | CYNTEC CO., LTD. | RR0510S-203-FTF | 5 | PR148,PR471,PR6007,PR6505,PR6524 |
| CS32152FB04 | RES CHIP 21.5K 1/16W +-1%(0402)EF | CYNTEC CO., LTD. | RR0510S-2152-FTF | 1 | PR834 |
| CS32212FB02 | RES CHIP 22.1K 1/16W +-1%(0402)EF | CYNTEC CO., LTD. | RR0510S-2212-FTF | 1 | PR6533 |
| CS32322FB03 | RES CHIP 23.2K 1/16W +-1%(0402)EF | CYNTEC CO., LTD. | RR0510S-2322-FTF | 4 | R762,R766,R771,R775 |
| CS32552FB06 | RES CHIP 25.5K 1/16W +-1%(0402)EF | CYNTEC CO., LTD. | RR0510S-2552-FTF | 3 | PR3789,PR3795,PR3963 |
| CS33002FB02 | RES CHIP 30K 1/16W +-1%(0402)EF | KOASPEER ELECTRONICS INC. | RK73H1EVTTP3002F | 5 | R1503,R1504,R1505,R1506,R750 |
| CS33012FB03 | RES CHIP 30.1K 1/16W +-1%(0402)EF | KOASPEER ELECTRONICS INC. | RK73H1EVTTP3012F | 2 | PR3821,PR5484 |
| CS33162FB02 | RES CHIP 31.6K 1/16W +-1%(0402)EF | CYNTEC CO., LTD. | RR0510S-3162-FTF | 1 | R2585 |
| CS33302FB00 | RES CHIP 33K 1/16W +-1%(0402)EF | KOASPEER ELECTRONICS INC. | RK73H1EVTTP3302F | 1 | R3907 |
| CS33572FB01 | RES CHIP 35.7K 1/16W +-1%(0402) EF | CYNTEC CO., LTD. | RR0510S-3572-FTF | 4 | R763,R767,R772,R776 |
| CS34022FB04 | RES CHIP 40.2K 1/16W +-1%(0402)EF | CYNTEC CO., LTD. | RR0510S-4022-FTF | 6 | PR113,PR157,PR230,PR290,PR376,PR53 |
| CS34702BB05 | RES CHIP 47K 1/16W +-0.1%(0402)EF | RALEC ELECTRONIC CO. | FTT024702BTH | 1 | PR831 |
| CS35492FB03 | RES CHIP 54.9K 1/16W +-1%(0402)EF | CYNTEC CO., LTD. | RR0510S-5492-FTF | 20 | R3461,R3463,R3464,R3492,R3494,R3498,R3508,R3510,R3511,R3513,R3514,R3521,R3522,R3523,R3524,R3525,R5,R6,R768,R777 |
| CS35602FB00 | RES CHIP 56K 1/16W +-1%(0402)EF | CYNTEC CO., LTD. | RR0510S-563-FTF | 1 | PR455 |
| CS36042FB04 | RES CHIP 60.4K 1/16W +-1%(0402)EF | CYNTEC CO., LTD. | RR0510S-6042-FTF | 2 | PR6005,PR6006 |
| CS36342FB04 | RES CHIP 63.4K 1/16W +-1%(0402)EF | CYNTEC CO., LTD. | RR0510S-6342-FTF | 1 | R3923 |
| CS37502BB01 | RES CHIP 75K 1/16W +-0.1%(0402)EF | EVER OHMS TECHNOLOGY CO., LTD. | CRG0402B75K0Q10Z | 2 | PR3926,PR3931 |
| CS38202FB01 | RES CHIP 82K 1/16W +-1% (0402)EF | CYNTEC CO., LTD. | RR0510S-823-FTF | 1 | R4901 |
| CS38452FB05 | RES CHIP 84.5K 1/16W +-1%(0402)EF | CYNTEC CO., LTD. | RR0510S-8452-FTF | 4 | R764,R769,R773,R778 |
| CS38662FB05 | RES CHIP 86.6K 1/16W +-1%(0402)EF | CYNTEC CO., LTD. | RR0510S-8662-FTF | 1 | PR8092 |
| CS41002FB09 | RES CHIP 100K 1/16W +-1%(0402)EF | CYNTEC CO., LTD. | RR0510S-104-FTF | 78 | R1289,R1440,R1442,R2346,R2528,R2828,R2830,R2832,R2838,R2919,R2920,R2927,R2933,R2934,R2935,R2941,R3030,R3035,R3132,R3207,R3232,R3235,R3321,R334,R336,R3436,R3437,R3438,R3439,R3449,R3452,R3475,R3504,R3665,R3796,R3797,R3799,R3816,R3825,R3833,R3976,R3977,R3978,R3979,R4013,R4015,R4128,R4129,R4130,R4140,R4141,R4142,R4156,R4167,R4168,R4169,R4515,R4548,R4552,R4554,R4559,R4561,R480,R554,R6041,R6043,R6501,R77,R79,R8,R80,R8093,R8096,R82,R83,R84,R8413,R9027 |
| CS41202FB05 | RES CHIP 120K 1/16W +-1%(0402)EF | CYNTEC CO., LTD. | RR0510S-124-FTF | 5 | PR1134,PR3912,PR3937,PR3982,PR3984 |
| CS41602FB05 | RES CHIP 160K 1/16W+-1%(0402)EF | CYNTEC CO., LTD. | RR0510S-164-FTF | 4 | PR3786,PR3805,PR3960,PR4000 |
| CS42002FB05 | RES CHIP 200K 1/16W +-1%(0402)EF | CYNTEC CO., LTD. | RR0510S-204-FTF | 2 | R1700,R4211 |
| CS51002FB05 | RES CHIP 1M 1/16W +-1%(0402)EF | CYNTEC CO., LTD. | RR0510S-105-FTF | 2 | R8117,R8123 |
| CS-5602FB01 | RES CHIP 5.6 1/16W 1%(0402)EF | WALSIN TECHNOLOGY CORPORATION | WR04W5R60FTR | 46 | PR101,PR102,PR109,PR110,PR135,PR136,PR189,PR190,PR197,PR198,PR203,PR209,PR210,PR215,PR258,PR259,PR266,PR267,PR272,PR278,PR279,PR322,PR323,PR330,PR331,PR348,PR349,PR354,PR360,PR361,PR366,PR372,PR373,PR420,PR424,PR428,PR432,PR6554,PR6562,PR6623,PR6629,PR81,PR82,PR89,PR90,PR95 |
| CS61002FB02 | RES CHIP 10M 1/16W +-1%(0402)EF | TA-I TECHNOLOGY CO.,LTD. | RM04FTW1005 | 9 | PR4522,PR4523,PR4524,PR4525,PR4526,PR4527,PR4528,R432,R571 |
| CS62002FB01 | RES CHIP 20M 1/16W +-1%(0402)EF | RALEC ELECTRONIC CO. | FTT022005FTH | 2 | R433,R572 |
| CV+10G0MZ04 | IND SMD 100NH 20% 16A(HCBS4545-101) | DELTA ELECTRONIC IND. CO., LTD. DELTA ELECTRONICS COMPONENT(WUJIANG)LTD | HCBS4545-101 | 15 | L10,L12,L14,L21,L23,L4,L6,L8,PL24,PL56,PL6500,PL6503,PL6504,PL6510,PL8045 |
| CV+12^0EZ03 | IND SMD 120NH 15% 69A(PGL6312.121AHLT) | PULSE | PGL6312.121AHLT | 8 | PL27,PL39,PL50,PL6505,PL6506,PL6511,PL6512,PL9 |
| CV+15^0TZ04 | IND SMD 150NH 15% 82A(PGL6303.151HLT) | PULSE | PGL6303.151HLT | 38 | PL10,PL11,PL13,PL14,PL15,PL17,PL18,PL20,PL21,PL28,PL29,PL31,PL32,PL33,PL35,PL36,PL38,PL40,PL41,PL43,PL44,PL45,PL47,PL48,PL51,PL52,PL59,PL60,PL61,PL63,PL64,PL66,PL67,PL68,PL69,PL7,PL70,PL8 |
| CV+22Y0EZ00 | IND SMD 0.22UH 15% 33A(HCME656510Q-221QL | DELTA ELECTRONIC IND. CO., LTD. DELTA ELECTRONICS COMPONENT(WUJIANG)LTD | HCME656510Q-221QL | 4 | PL16,PL34,PL46,PL62 |
| CV-10I0MZ01 | IND SMD 1.0UH +-20% 18A(PCMC104T-1R0MN) | CYNTEC CO., LTD. | PCMC104T-1R0MN | 2 | PL57,PL78 |
| CV-10U0MZ01 | IND SMD 1UH +-20% 29A(PCMC135T-1R0MF) | CYNTEC CO., LTD. | PCMC135T-1R0MF | 2 | PL6501,PL6502 |
| CV-15^0MZ02 | IND SMD 1.5UH 20% 53A(EM-15AM17VG1-QS) | TRIO TECHNOLGY CO., LTD. | EM-15AM17VG1-QS | 1 | PL8066 |
| CV-15I0MZ28 | IND SMD 1.5UH+-20% 18A(PCMC063T-1R5MN) | CYNTEC CO., LTD. | PCMC063T-1R5MN | 1 | PL72 |
| CV-2280MZ15 | IND SMD 2.2UH +-20% 8A(PCMC063T-2R2MN) | CYNTEC CO., LTD. | PCMC063T-2R2MN | 1 | PL6001 |
| CV-3360MZ07 | IND SMD 3.3UH,6A20%(PCMC063T-3R3MN) | CYNTEC CO., LTD. | PCMC063T-3R3MN | 1 | PL6000 |
| CV-47A0MZ10 | IND SMD 4.7UH +-20% 10A(PCMB104E-4R7MS) | CYNTEC CO., LTD. | PCMB104E-4R7MS | 1 | PL8065 |
| CVA50^0MZ09 | IND SMD 50NH 20% 86A(PG2292.500HLT) | PULSE | PG2292.500HLT | 8 | PL12,PL19,PL30,PL37,PL42,PL49,PL53,PL65 |
| CVA90^0KZ13 | IND SMD 90NH 10% 155A(PG2323.900HLT) | PULSE | PG2323.900HLT | 4 | PL22,PL23,PL54,PL55 |
| CX1PG221001 | EMI FILTER BLM21PG221SN1D(220,100M,2A) | MURATA ERIE N.A. INC TAIWAN BRANCH Okayama Murata Mfg.Co.,Ltd.Wakura Murata Mfg. Co., Ltd. (Peregrine Semiconductor Corp) | BLM21PG221SN1D | 2 | L6000,L6001 |
| CX220TN1001 | EMI FILTER BLM18SN220TN1D(22,8000MA) | MURATA ERIE N.A. INC TAIWAN BRANCH Okayama Murata Mfg.Co.,Ltd.Wakura Murata Mfg. Co., Ltd. (Peregrine Semiconductor Corp) | BLM18SN220TN1D | 6 | PL26,PL6002,PL6003,PL71,PL77,PL8064 |
| CX300SN1000 | EMI FILTER BLM21SN300SN1D(30,8.5A) | MURATA ERIE N.A. INC TAIWAN BRANCH Okayama Murata Mfg.Co.,Ltd.Wakura Murata Mfg. Co., Ltd. (Peregrin......(Skip) | BLM21SN300SN1D | 8 | L11,L13,L18,L22,L3,L5,L7,L9 |
| CX5PD121000 | EMI FILTER BLM15PD121SN1D(120OHM,1300MA) | MURATA ERIE N.A. INC TAIWAN BRANCH Okayama Murata Mfg.Co.,Ltd.Wakura Murata Mfg. Co., Ltd. (Peregrine Semiconductor Corp) | BLM15PD121SN1D | 8 | L26,L27,L28,L29,L30,L31,L32,L33 |
| CX601T05003 | EMI FILTER FCM2012KF-601T05(600,0.5A) | TAI-TECH ADVANCED ELECTRONICS CO. | FCM2012KF-601T05 | 5 | L1,L17,L19,L2,L20 |
| CX8PG300001 | EMI FILTER CHIP BLM18PG300SN1D(30,1A) | MURATA ERIE N.A. INC TAIWAN BRANCH Okayama Murata Mfg.Co.,Ltd.Wakura Murata Mfg. Co., Ltd. (Peregrine Semiconductor Corp) | BLM18PG300SN1D | 4 | L15,L16,L24,L25 |
| DAF0TMB3IC0 | PCB F0TG MB 8R(18L,471.8*441.99,C) | WUS PRINTED CIRCUIT CO., LTD. | DAF0TMB3IC0 REV C | 1 | PCB |
| DFHD03MS213 | CONN DIP HEADER 3P 1R MS(P2.54,H8.6) | PINREX TECHNOLOGY CORP | 210-HP1-030BR1 | 7 | JP10,JP12,JP4003,JP6000,JP6001,JP6500,PJ1 |
| DFHD04MS460 | CONN DIP HEADER 4P 1R MS(P2,H6) | (FOXCONN) HON HAI PRECISION INDUSTRY KANG ZHUN PRESION TOOLING(KUN SHAN)CO.,LTD FuYu Precision Compo......(Skip) | HFK1040-L0P1L-7H | 2 | J13,J8 |
| DFHD06MS263 | CONN DIP HEADER 6P 2R MS(P2.54,H8.38) | (FOXCONN) HON HAI PRECISION INDUSTRY KANG ZHUN PRESION TOOLING(KUN SHAN)CO.,LTD FuYu Precision Compo......(Skip) | HBC1031-L200D-8H | 1 | J6 |
| DFHD08MS197 | CONN DIP HEADER 8P 1R MS(P2.54,H8.38) | (FOXCONN) HON HAI PRECISION INDUSTRY KANG ZHUN PRESION TOOLING(KUN SHAN)CO.,LTD FuYu Precision Compo......(Skip) | HBB1081-L200D-8H | 1 | J57 |
| DFHD08MS385 | CONN SMD HEADER 8P 2R MS(P1.27,H5.5) | AMPHENOL EAST ASIA LIMITED (Amphenol-TCS) (Shanghai Amphenol Airwave Communication Electronics Co.,Ltd) | G802M0083150RD3HR | 4 | J48,J49,J5,J7 |
| DFHD10MS117 | CONN DIP HEADER 10P 2R MS(P2.54, H8.38) | (FOXCONN) HON HAI PRECISION INDUSTRY KANG ZHUN PRESION TOOLING(KUN SHAN)CO.,LTD FuYu Precision Compo......(Skip) | HBC1051-L300D-8H | 1 | J212 |
| DFHD20MS153 | CONN SMD HEADER 20P 2R MS(P1.27,H6.14) | (FOXCONN) HON HAI PRECISION INDUSTRY KANG ZHUN PRESION TOOLING(KUN SHAN)CO.,LTD FuYu Precision Compo......(Skip) | HSU2101-L0000-7H | 1 | J54 |
| DFHS02FR062 | CONN DIP HOUSING 2P 1R FR(P20,H8.80) | LOTES(CHIA TSE TERMINAL INDUSTRYLOTES SUZHOU CO.,LTD | AAA-BAT-029-Y19 | 1 | BT2 |
| DFHS56FS022 | CONN SMD HOUSING 56P 2R FS(P0.6, H9.25) | TYCO ELECTRONICS TAIWAN CO.,LTD. (Raychem)COEY MAGNETICS(Sensormatic Hong Kong Limited) TE Connectivity | 1-2327679-3 | 1 | J90 |
| DFHSG8FR011 | CONN SMD HOUSING 168P 2R FR(P0.6,H5.35) | AMPHENOL EAST ASIA LIMITED (Amphenol-TCS) (Shanghai Amphenol Airwave Communication Electronics Co.,Ltd) | ME1016810202011 | 3 | J35,J38,J41 |
| DFHST8FS540 | CONN SMD HS DDR5 288P 2R FS(P0.85,H21.3) | (FOXCONN) HON HAI PRECISION INDUSTRY KANG ZHUN PRESION TOOLING(KUN SHAN)CO.,LTD FuYu Precision Compo......(Skip) | ATF5893-Q2B2E-1H | 24 | J1,J100,J102,J15,J16,J17,J18,J19,J20,J21,J23,J24,J26,J27,J28,J29,J30,J32,J33,J37,J67,J68,J69,J99 |
| DGA^6000028 | SOCKET SP5 6096P LGA(P0.94,H3.9) | (FOXCONN) HON HAI PRECISION INDUSTRY KANG ZHUN PRESION TOOLING(KUN SHAN)CO.,LTD FuYu Precision Compo......(Skip) | PE60963-01AN0-1H | 2 | U25,U26 |
| DHD00010F01 | SWITCH SMD DIP(DHNF-10F-Q-T/R) | Diptronics Manufacturing Inc. | DHNF-10F-Q-T/R | 1 | SW1 |
| DKK00XFU000 | FUSE SMD 20A/125V(FAST,UL/CSA) | LITTELFUSE INC. | 0456020.ER | 1 | FS1 |
| FBF0C045010 | THUMB SCREW SMT F0C(FBF0C045,REV3A)FVT | Fivetech Technology Inc. | FBF0C04501 | 21 | H100,H101,H102,H103,H104,H105,H106,H128,H86,H87,H88,H89,H91,H92,H93,H94,H95,H96,H97,H98,H99 |
| MBF0E004010 | NUT MB TPM M3 F0E(MBF0E004,REV3B)STEEL | HUANG YIH  Industrial Co., Ltd(Rayhome) | MBF0E00401 | 1 | H6002 |
| MBS5K007010 | MB NUT M2*3 S5K(MBS5K007,3A)STEEL | SCREW TECH INDUDTRY CO., LTD. | MBS5K00701 | 24 | H10,H11,H12,H13,H2,H21,H22,H3,H33,H34,H37,H38,H43,H44,H49,H5,H50,H53,H54,H6000,H6001,H8,H8027,H8028 |
| 4SF0TRA0080 | F0TG BRACKET ASSY HS 82F | CHENMING ELECTRONIC MANUFACTORY (Chenming Mold Ind. Corp.) | 4SF0TRA008 | 2 | RT_L_BP,RT_R_BP |
| AHL03003097 | BATTERY LI,3V,220MAH(BCR2032HT) | Double Best Corporation Limited (DBV) | BCR2032HT | 1 | BATTERY_BT2 |
| CC72703MD38 | CAPOSCON DIP 270U16V(20%,ESR10,6.3*8)NPN | NIPPON CHEMI-CON | APSG160ETD271MF08J | 13 | PC3,PC101,PC104,PC164,PC220,PC272,PC273,PC336,PC491,PC492,PC522,PC566,PC596 |
| CC75601MD16 | CAPOS DIP 560U 6.3V(+-20%,ESR8,6.3*8)NPN | NIPPON CHEMI-CON | APSE6R3ETD561MF08S | 2 | PC1866,PC1867 |
| DEJP0020021 | MINI JUMPER 2.54MM(5.0*2.4*6.0) BK | ACES ELECTRONIC CO., LTD. | 57928-00211-V01 | 4 | JP12_12,JP4003_12,JP6000_12,JP6001_12 |
| DFHD60MR024 | CONN DIP HEADER 60P 4R MR(P2.54,H12.57) | AMPHENOL EAST ASIA LIMITED (Amphenol-TCS) (Shanghai Amphenol Airwave Communication Electronics Co.,Ltd) | 10106263-6003K02LF | 1 | J45 |
| DFHS03FR030 | CONN DIP HOUSING 3P 1R FR(H14.7) | AMPHENOL EAST ASIA LIMITED (Amphenol-TCS) (Shanghai Amphenol Airwave Communication Electronics Co.,Ltd) | 10165288-101LF | 2 | J122,J123 |
| DFHS56FR016 | CONN SMD HS 56P 2R FR(P0.6, H20.125) | TYCO ELECTRONICS TAIWAN CO.,LTD. (Raychem)COEY MAGNETICS(Sensormatic Hong Kong Limited) TE Connectivity | 2360871-1 | 1 | J90_CON |
| DFHSB2FR012 | CONN DIP HOUSING 112P 8R FR(P1.2,H17.9) | BERG ELECTRONICS (FCI) | 10137002-101LF | 7 | J105,J106,J107,J108,J109,J110,J111 |
| DFHSG0FR007 | CONN DIP HOUSING 160P 8R FR(P1.2,H25.1) | BERG ELECTRONICS (FCI) | 10131762-101LF | 1 | J112 |
| DGRA^600000 | CPU SKTSUP LGA6096 SP5 SR(FOX) | (FOXCONN) HON HAI PRECISION INDUSTRY KANG ZHUN PRESION TOOLING(KUN SHAN)CO.,LTD FuYu Precision Compo......(Skip) | WNMAL60-1NAN0-EH | 2 | U25_SRM,U26_SRM |
| DGRA^600020 | CPU SKTSUP LGA6096 SP5 BP(FOX) | (FOXCONN) HON HAI PRECISION INDUSTRY KANG ZHUN PRESION TOOLING(KUN SHAN)CO.,LTD FuYu Precision Compo......(Skip) | WNMAP06-02AN0-EH | 2 | U25_BP,U26_BP |
| FBF0C041010 | MB AIR BAFFLE GUIDE PIN F0C(FBF0C041,3A) | ASCEND TOWER ENTERPRISE CO.,LTD (ASCEND TOP ENTERPRISE CO., LTD) | FBF0C04101 | 1 | H115 |
| FBF0T006010 | HANDLE MB TOP F0T(FBF0T006,R3A)FVT | Fivetech Technology Inc. | FBF0T00601 | 1 | HANDLE_1 |
| FBF0T134010 | VR HS 31F EX F0TG(FBF0T134,3A)ART | AURAS TECHNOLOGY COMPANY (AURAS TECHNOLOGY (KUNSHAN) CO., LTD)  Pel horng(GuangZhou) Technology Co.,......(Skip) | FBF0T13401 | 1 | VR_R |
| FBF0T135010 | VR HS 33F EX F0TG(FBF0T135,3A)ART | AURAS TECHNOLOGY COMPANY (AURAS TECHNOLOGY (KUNSHAN) CO., LTD)  Pel horng(GuangZhou) Technology Co.,......(Skip) | FBF0T13501 | 1 | VR_L |
| FBF0T136010 | VR HS 32F EX F0TG(FBF0T136,3A)ART | AURAS TECHNOLOGY COMPANY (AURAS TECHNOLOGY (KUNSHAN) CO., LTD)  Pel horng(GuangZhou) Technology Co.,......(Skip) | FBF0T13601 | 2 | VR_REAR1,VR_REAR2 |
| FBF0T137010 | VR HS 9F EX F0TG(FBF0T137,3A)ART | AURAS TECHNOLOGY COMPANY (AURAS TECHNOLOGY (KUNSHAN) CO., LTD)  Pel horng(GuangZhou) Technology Co.,......(Skip) | FBF0T13701 | 2 | VR_HS1,VR_HS2 |
| FBF0T141010 | HANDLE MB F0T(FBF0T141,R3A)FVT | Fivetech Technology Inc. | FBF0T14101 | 1 | HANDLE_2 |
| FBF0T173010 | CHIPS HS 9F EX F0TG(FBF0T173,3A)ART | AURAS TECHNOLOGY COMPANY (AURAS TECHNOLOGY (KUNSHAN) CO., LTD)  Pel horng(GuangZhou) Technology Co.,......(Skip) | FBF0T17301 | 2 | RT_0V9_L,RT_0V9_R |
| FBF0T175010 | CHIPS HS 82F HP F0TG(FBF0T175,3A)ART | AURAS TECHNOLOGY COMPANY (AURAS TECHNOLOGY (KUNSHAN) CO., LTD)  Pel horng(GuangZhou) Technology Co.,......(Skip) | FBF0T17501 | 2 | RT_L,RT_R |
| FBF0T177010 | CHIPS HS 9F DC F0TG(FBF0T177,3A)ART | AURAS TECHNOLOGY COMPANY (AURAS TECHNOLOGY (KUNSHAN) CO., LTD)  Pel horng(GuangZhou) Technology Co.,......(Skip) | FBF0T17701 | 1 | RT_1V8_VR |
| HCF0A001010 | LABEL SERIAL PL F0A(HCF0A001,3B) | CHENG MAY ENTERPRISE CO.,LTD. | HCF0A00101 | 1 | LBL_2 |
| HCLU2002010 | EFI BIOS LABEL LU2(HCLU2002,REV3A) | AMERICAN MEGATRENDS INC. | HCLU200201 | 1 | BIOS_LABEL |
| HCS6I019010 | LABEL SERIAL PL S6I(HCS6I019,3A) | CHENG MAY ENTERPRISE CO.,LTD. | HCS6I01901 | 1 | LBL_1 |
| HCT70001013 | MB LABEL (HCT70001,REV3A) | CHENG MAY ENTERPRISE CO.,LTD. | HCT70001 | 1 | REWORK LABEL |
| MM16045P000 | SCREW M1.6*4.5-P(NI,NYLOK,D3.2,T1.3)STL | SCREW TECH INDUDTRY CO., LTD. | MM16045P000 | 2 | H76_S,H77_S |
| MS30050I070 | SCREW M3.0*5.0-I(NI) (NYLOK)IRON | SCREW TECH INDUDTRY CO., LTD. | M30050I07 | 2 | J122_S1,J123_S2 |
| MS30050I290 | SCREW M3*5-I(ZN)(NYLOK)STEEL(D8,T1.5) | SCREW TECH INDUDTRY CO., LTD. | M30050I29 | 1 | H115_S |
| MS50060PI60 | SCREW M5.0*6.0-P(NI)(NYLOK)STEEL | SCREW TECH INDUDTRY CO., LTD. | M50060PI6 | 2 |  |
| MU06060BCI2 | SCREW #6-32UNC*6-B(NYLOK)IRON | SCREW TECH INDUDTRY CO., LTD. | MU06060BCI2 | 2 |  |
